G04 ================== begin FILE IDENTIFICATION RECORD ==================*
G04 Layout Name:  12433-1M.brd*
G04 Film Name:    DRILL*
G04 File Format:  Gerber RS274X*
G04 File Origin:  Cadence Allegro 16.2-S037*
G04 Origin Date:  Fri Dec 07 18:55:05 2012*
G04 *
G04 Layer:  MANUFACTURING/NCLEGEND-1-4*
G04 Layer:  MANUFACTURING/DRILL SIZE*
G04 Layer:  DRAWING FORMAT/LAYER_PCB_STORY*
G04 Layer:  DRAWING FORMAT/LAYER_DRILL*
G04 Layer:  BOARD GEOMETRY/PANEL_OUTLINE*
G04 *
G04 Offset:    (0.00 0.00)*
G04 Mirror:    No*
G04 Mode:      Positive*
G04 Rotation:  0*
G04 FullContactRelief:  No*
G04 UndefLineWidth:     6.00*
G04 ================== end FILE IDENTIFICATION RECORD ====================*
%FSLAX35Y35*MOIN*%
%IR0*IPPOS*OFA0.00000B0.00000*MIA0B0*SFA1.00000B1.00000*%
%AMMACRO22*
1,1,.006,0.0,.0995*
20,1,.006,0.0,.0995,0.0,.0995,0.0*
1,1,.006,0.0,.0995*
20,1,.006,0.0,.0995,.017278,.097988,0.0*
1,1,.006,.017278,.097988*
20,1,.006,.017278,.097988,.034031,.093499,0.0*
1,1,.006,.034031,.093499*
20,1,.006,.034031,.093499,.04975,.08617,0.0*
1,1,.006,.04975,.08617*
20,1,.006,.04975,.08617,.063957,.076221,0.0*
1,1,.006,.063957,.076221*
20,1,.006,.063957,.076221,.076221,.063957,0.0*
1,1,.006,.076221,.063957*
20,1,.006,.076221,.063957,.08617,.04975,0.0*
1,1,.006,.08617,.04975*
20,1,.006,.08617,.04975,.093499,.034031,0.0*
1,1,.006,.093499,.034031*
20,1,.006,.093499,.034031,.097988,.017278,0.0*
1,1,.006,.097988,.017278*
20,1,.006,.097988,.017278,.0995,0.0,0.0*
1,1,.006,.0995,0.0*
20,1,.006,.0995,0.0,.097988,-.017278,0.0*
1,1,.006,.097988,-.017278*
20,1,.006,.097988,-.017278,.093499,-.034031,0.0*
1,1,.006,.093499,-.034031*
20,1,.006,.093499,-.034031,.08617,-.04975,0.0*
1,1,.006,.08617,-.04975*
20,1,.006,.08617,-.04975,.076221,-.063957,0.0*
1,1,.006,.076221,-.063957*
20,1,.006,.076221,-.063957,.063957,-.076221,0.0*
1,1,.006,.063957,-.076221*
20,1,.006,.063957,-.076221,.04975,-.08617,0.0*
1,1,.006,.04975,-.08617*
20,1,.006,.04975,-.08617,.034031,-.093499,0.0*
1,1,.006,.034031,-.093499*
20,1,.006,.034031,-.093499,.017278,-.097988,0.0*
1,1,.006,.017278,-.097988*
20,1,.006,.017278,-.097988,0.0,-.0995,0.0*
1,1,.006,0.0,-.0995*
20,1,.006,0.0,-.0995,0.0,-.0995,0.0*
1,1,.006,0.0,-.0995*
20,1,.006,0.0,-.0995,-.017278,-.097988,0.0*
1,1,.006,-.017278,-.097988*
20,1,.006,-.017278,-.097988,-.034031,-.093499,0.0*
1,1,.006,-.034031,-.093499*
20,1,.006,-.034031,-.093499,-.04975,-.08617,0.0*
1,1,.006,-.04975,-.08617*
20,1,.006,-.04975,-.08617,-.063957,-.076221,0.0*
1,1,.006,-.063957,-.076221*
20,1,.006,-.063957,-.076221,-.076221,-.063957,0.0*
1,1,.006,-.076221,-.063957*
20,1,.006,-.076221,-.063957,-.08617,-.04975,0.0*
1,1,.006,-.08617,-.04975*
20,1,.006,-.08617,-.04975,-.093499,-.034031,0.0*
1,1,.006,-.093499,-.034031*
20,1,.006,-.093499,-.034031,-.097988,-.017278,0.0*
1,1,.006,-.097988,-.017278*
20,1,.006,-.097988,-.017278,-.0995,0.0,0.0*
1,1,.006,-.0995,0.0*
20,1,.006,-.0995,0.0,-.097988,.017278,0.0*
1,1,.006,-.097988,.017278*
20,1,.006,-.097988,.017278,-.093499,.034031,0.0*
1,1,.006,-.093499,.034031*
20,1,.006,-.093499,.034031,-.08617,.04975,0.0*
1,1,.006,-.08617,.04975*
20,1,.006,-.08617,.04975,-.076221,.063957,0.0*
1,1,.006,-.076221,.063957*
20,1,.006,-.076221,.063957,-.063957,.076221,0.0*
1,1,.006,-.063957,.076221*
20,1,.006,-.063957,.076221,-.04975,.08617,0.0*
1,1,.006,-.04975,.08617*
20,1,.006,-.04975,.08617,-.034031,.093499,0.0*
1,1,.006,-.034031,.093499*
20,1,.006,-.034031,.093499,-.017278,.097988,0.0*
1,1,.006,-.017278,.097988*
20,1,.006,-.017278,.097988,0.0,.0995,0.0*
1,1,.006,0.0,.0995*
1,1,.006,0.0,-.04975*
20,1,.006,0.0,-.04975,.01161,-.04809,0.0*
1,1,.006,.01161,-.04809*
20,1,.006,.01161,-.04809,.02487,-.04312,0.0*
1,1,.006,.02487,-.04312*
20,1,.006,.02487,-.04312,.03317,-.03483,0.0*
1,1,.006,.03317,-.03483*
20,1,.006,.03317,-.03483,.03648,-.02322,0.0*
1,1,.006,.03648,-.02322*
20,1,.006,.03648,-.02322,.03317,-.01161,0.0*
1,1,.006,.03317,-.01161*
20,1,.006,.03317,-.01161,.02322,-.00166,0.0*
1,1,.006,.02322,-.00166*
20,1,.006,.02322,-.00166,.00829,.00332,0.0*
1,1,.006,.00829,.00332*
20,1,.006,.00829,.00332,-.00829,.00332,0.0*
1,1,.006,-.00829,.00332*
20,1,.006,-.00829,.00332,-.01824,.00663,0.0*
1,1,.006,-.01824,.00663*
20,1,.006,-.01824,.00663,-.02654,.01492,0.0*
1,1,.006,-.02654,.01492*
20,1,.006,-.02654,.01492,-.02985,.02653,0.0*
1,1,.006,-.02985,.02653*
20,1,.006,-.02985,.02653,-.02487,.03814,0.0*
1,1,.006,-.02487,.03814*
20,1,.006,-.02487,.03814,-.01327,.04643,0.0*
1,1,.006,-.01327,.04643*
20,1,.006,-.01327,.04643,0.0,.04975,0.0*
1,1,.006,0.0,.04975*
20,1,.006,0.0,.04975,.01327,.04643,0.0*
1,1,.006,.01327,.04643*
20,1,.006,.01327,.04643,.02487,.03814,0.0*
1,1,.006,.02487,.03814*
20,1,.006,.02487,.03814,.02985,.02653,0.0*
1,1,.006,.02985,.02653*
20,1,.006,.02985,.02653,.02653,.01492,0.0*
1,1,.006,.02653,.01492*
20,1,.006,.02653,.01492,.01824,.00663,0.0*
1,1,.006,.01824,.00663*
20,1,.006,.01824,.00663,.00829,.00332,0.0*
1,1,.006,.00829,.00332*
20,1,.006,.00829,.00332,-.00829,.00332,0.0*
1,1,.006,-.00829,.00332*
20,1,.006,-.00829,.00332,-.02322,-.00166,0.0*
1,1,.006,-.02322,-.00166*
20,1,.006,-.02322,-.00166,-.03317,-.01161,0.0*
1,1,.006,-.03317,-.01161*
20,1,.006,-.03317,-.01161,-.03648,-.02322,0.0*
1,1,.006,-.03648,-.02322*
20,1,.006,-.03648,-.02322,-.03317,-.03483,0.0*
1,1,.006,-.03317,-.03483*
20,1,.006,-.03317,-.03483,-.02487,-.04312,0.0*
1,1,.006,-.02487,-.04312*
20,1,.006,-.02487,-.04312,-.01161,-.04809,0.0*
1,1,.006,-.01161,-.04809*
20,1,.006,-.01161,-.04809,0.0,-.04975,0.0*
1,1,.006,0.0,-.04975*
%
%ADD22MACRO22*%
%AMMACRO20*
1,1,.006,-.0495,0.0*
20,1,.006,-.0495,0.0,-.048748,.008596,0.0*
1,1,.006,-.048748,.008596*
20,1,.006,-.048748,.008596,-.046515,.01693,0.0*
1,1,.006,-.046515,.01693*
20,1,.006,-.046515,.01693,-.042868,.02475,0.0*
1,1,.006,-.042868,.02475*
20,1,.006,-.042868,.02475,-.037919,.031818,0.0*
1,1,.006,-.037919,.031818*
20,1,.006,-.037919,.031818,-.031818,.037919,0.0*
1,1,.006,-.031818,.037919*
20,1,.006,-.031818,.037919,-.02475,.042868,0.0*
1,1,.006,-.02475,.042868*
20,1,.006,-.02475,.042868,-.01693,.046515,0.0*
1,1,.006,-.01693,.046515*
20,1,.006,-.01693,.046515,-.008596,.048748,0.0*
1,1,.006,-.008596,.048748*
20,1,.006,-.008596,.048748,0.0,.0495,0.0*
1,1,.006,0.0,.0495*
20,1,.006,0.0,.0495,.008596,.048748,0.0*
1,1,.006,.008596,.048748*
20,1,.006,.008596,.048748,.01693,.046515,0.0*
1,1,.006,.01693,.046515*
20,1,.006,.01693,.046515,.02475,.042868,0.0*
1,1,.006,.02475,.042868*
20,1,.006,.02475,.042868,.031818,.037919,0.0*
1,1,.006,.031818,.037919*
20,1,.006,.031818,.037919,.037919,.031818,0.0*
1,1,.006,.037919,.031818*
20,1,.006,.037919,.031818,.042868,.02475,0.0*
1,1,.006,.042868,.02475*
20,1,.006,.042868,.02475,.046515,.01693,0.0*
1,1,.006,.046515,.01693*
20,1,.006,.046515,.01693,.048748,.008596,0.0*
1,1,.006,.048748,.008596*
20,1,.006,.048748,.008596,.0495,0.0,0.0*
1,1,.006,.0495,0.0*
20,1,.006,.0495,0.0,.0495,0.0,0.0*
1,1,.006,.0495,0.0*
20,1,.006,.0495,0.0,.048748,-.008596,0.0*
1,1,.006,.048748,-.008596*
20,1,.006,.048748,-.008596,.046515,-.01693,0.0*
1,1,.006,.046515,-.01693*
20,1,.006,.046515,-.01693,.042868,-.02475,0.0*
1,1,.006,.042868,-.02475*
20,1,.006,.042868,-.02475,.037919,-.031818,0.0*
1,1,.006,.037919,-.031818*
20,1,.006,.037919,-.031818,.031818,-.037919,0.0*
1,1,.006,.031818,-.037919*
20,1,.006,.031818,-.037919,.02475,-.042868,0.0*
1,1,.006,.02475,-.042868*
20,1,.006,.02475,-.042868,.01693,-.046515,0.0*
1,1,.006,.01693,-.046515*
20,1,.006,.01693,-.046515,.008596,-.048748,0.0*
1,1,.006,.008596,-.048748*
20,1,.006,.008596,-.048748,0.0,-.0495,0.0*
1,1,.006,0.0,-.0495*
20,1,.006,0.0,-.0495,-.008596,-.048748,0.0*
1,1,.006,-.008596,-.048748*
20,1,.006,-.008596,-.048748,-.01693,-.046515,0.0*
1,1,.006,-.01693,-.046515*
20,1,.006,-.01693,-.046515,-.02475,-.042868,0.0*
1,1,.006,-.02475,-.042868*
20,1,.006,-.02475,-.042868,-.031818,-.037919,0.0*
1,1,.006,-.031818,-.037919*
20,1,.006,-.031818,-.037919,-.037919,-.031818,0.0*
1,1,.006,-.037919,-.031818*
20,1,.006,-.037919,-.031818,-.042868,-.02475,0.0*
1,1,.006,-.042868,-.02475*
20,1,.006,-.042868,-.02475,-.046515,-.01693,0.0*
1,1,.006,-.046515,-.01693*
20,1,.006,-.046515,-.01693,-.048748,-.008596,0.0*
1,1,.006,-.048748,-.008596*
20,1,.006,-.048748,-.008596,-.0495,0.0,0.0*
1,1,.006,-.0495,0.0*
20,1,.006,-.0495,0.0,-.0495,0.0,0.0*
1,1,.006,-.0495,0.0*
1,1,.006,-.01403,-.01898*
20,1,.006,-.01403,-.01898,-.00825,-.0231,0.0*
1,1,.006,-.00825,-.0231*
20,1,.006,-.00825,-.0231,-.00165,-.02475,0.0*
1,1,.006,-.00165,-.02475*
20,1,.006,-.00165,-.02475,.00495,-.0231,0.0*
1,1,.006,.00495,-.0231*
20,1,.006,.00495,-.0231,.01072,-.01815,0.0*
1,1,.006,.01072,-.01815*
20,1,.006,.01072,-.01815,.01485,-.01072,0.0*
1,1,.006,.01485,-.01072*
20,1,.006,.01485,-.01072,.0165,-.0033,0.0*
1,1,.006,.0165,-.0033*
20,1,.006,.0165,-.0033,.0165,.00577,0.0*
1,1,.006,.0165,.00577*
20,1,.006,.0165,.00577,.01485,.0132,0.0*
1,1,.006,.01485,.0132*
20,1,.006,.01485,.0132,.01072,.0198,0.0*
1,1,.006,.01072,.0198*
20,1,.006,.01072,.0198,.00577,.0231,0.0*
1,1,.006,.00577,.0231*
20,1,.006,.00577,.0231,0.0,.02475,0.0*
1,1,.006,0.0,.02475*
20,1,.006,0.0,.02475,-.0066,.0231,0.0*
1,1,.006,-.0066,.0231*
20,1,.006,-.0066,.0231,-.01155,.0198,0.0*
1,1,.006,-.01155,.0198*
20,1,.006,-.01155,.0198,-.01485,.01485,0.0*
1,1,.006,-.01485,.01485*
20,1,.006,-.01485,.01485,-.0165,.00825,0.0*
1,1,.006,-.0165,.00825*
20,1,.006,-.0165,.00825,-.01485,.00248,0.0*
1,1,.006,-.01485,.00248*
20,1,.006,-.01485,.00248,-.01072,-.0033,0.0*
1,1,.006,-.01072,-.0033*
20,1,.006,-.01072,-.0033,-.00577,-.0066,0.0*
1,1,.006,-.00577,-.0066*
20,1,.006,-.00577,-.0066,0.0,-.00743,0.0*
1,1,.006,0.0,-.00743*
20,1,.006,0.0,-.00743,.0066,-.00578,0.0*
1,1,.006,.0066,-.00578*
20,1,.006,.0066,-.00578,.01155,-.00165,0.0*
1,1,.006,.01155,-.00165*
20,1,.006,.01155,-.00165,.0165,.00577,0.0*
1,1,.006,.0165,.00577*
%
%ADD20MACRO20*%
%AMMACRO16*
1,1,.006,.006,0.0*
20,1,.006,.006,0.0,-.006,0.0,0.0*
1,1,.006,-.006,0.0*
1,1,.006,0.0,.006*
20,1,.006,0.0,.006,0.0,-.006,0.0*
1,1,.006,0.0,-.006*
1,1,.006,.003,0.0*
20,1,.006,.003,0.0,.003,.006,0.0*
1,1,.006,.003,.006*
20,1,.006,.003,.006,.0018,.0048,0.0*
1,1,.006,.0018,.0048*
1,1,.006,.0018,0.0*
20,1,.006,.0018,0.0,.0042,0.0,0.0*
1,1,.006,.0042,0.0*
%
%ADD16MACRO16*%
%AMMACRO21*
1,1,.006,.008491,-.0205*
20,1,.006,.008491,-.0205,-.008491,-.0205,0.0*
1,1,.006,-.008491,-.0205*
20,1,.006,-.008491,-.0205,-.0205,-.008491,0.0*
1,1,.006,-.0205,-.008491*
20,1,.006,-.0205,-.008491,-.0205,.008491,0.0*
1,1,.006,-.0205,.008491*
20,1,.006,-.0205,.008491,-.008491,.0205,0.0*
1,1,.006,-.008491,.0205*
20,1,.006,-.008491,.0205,.008491,.0205,0.0*
1,1,.006,.008491,.0205*
20,1,.006,.008491,.0205,.0205,.008491,0.0*
1,1,.006,.0205,.008491*
20,1,.006,.0205,.008491,.0205,-.008491,0.0*
1,1,.006,.0205,-.008491*
20,1,.006,.0205,-.008491,.008491,-.0205,0.0*
1,1,.006,.008491,-.0205*
1,1,.006,-.00752,-.00718*
20,1,.006,-.00752,-.00718,-.00547,-.00888,0.0*
1,1,.006,-.00547,-.00888*
20,1,.006,-.00547,-.00888,-.00308,-.00991,0.0*
1,1,.006,-.00308,-.00991*
20,1,.006,-.00308,-.00991,0.0,-.01025,0.0*
1,1,.006,0.0,-.01025*
20,1,.006,0.0,-.01025,.00308,-.00957,0.0*
1,1,.006,.00308,-.00957*
20,1,.006,.00308,-.00957,.00547,-.0082,0.0*
1,1,.006,.00547,-.0082*
20,1,.006,.00547,-.0082,.00718,-.00581,0.0*
1,1,.006,.00718,-.00581*
20,1,.006,.00718,-.00581,.00752,-.00308,0.0*
1,1,.006,.00752,-.00308*
20,1,.006,.00752,-.00308,.00683,-.00034,0.0*
1,1,.006,.00683,-.00034*
20,1,.006,.00683,-.00034,.00512,.00137,0.0*
1,1,.006,.00512,.00137*
20,1,.006,.00512,.00137,.00273,.00273,0.0*
1,1,.006,.00273,.00273*
20,1,.006,.00273,.00273,.00034,.00307,0.0*
1,1,.006,.00034,.00307*
20,1,.006,.00034,.00307,-.00205,.00273,0.0*
1,1,.006,-.00205,.00273*
20,1,.006,-.00205,.00273,-.00512,.00137,0.0*
1,1,.006,-.00512,.00137*
20,1,.006,-.00512,.00137,-.0041,.01025,0.0*
1,1,.006,-.0041,.01025*
20,1,.006,-.0041,.01025,.00512,.01025,0.0*
1,1,.006,.00512,.01025*
%
%ADD21MACRO21*%
%AMMACRO12*
1,1,.006,.008,.008*
20,1,.006,.008,.008,.008,-.008,0.0*
1,1,.006,.008,-.008*
20,1,.006,.008,-.008,-.008,-.008,0.0*
1,1,.006,-.008,-.008*
20,1,.006,-.008,-.008,-.008,.008,0.0*
1,1,.006,-.008,.008*
20,1,.006,-.008,.008,.008,.008,0.0*
1,1,.006,.008,.008*
1,1,.006,-.00253,.00267*
20,1,.006,-.00253,.00267,-.00173,.00347,0.0*
1,1,.006,-.00173,.00347*
20,1,.006,-.00173,.00347,-.0008,.00387,0.0*
1,1,.006,-.0008,.00387*
20,1,.006,-.0008,.00387,.00027,.004,0.0*
1,1,.006,.00027,.004*
20,1,.006,.00027,.004,.0016,.00373,0.0*
1,1,.006,.0016,.00373*
20,1,.006,.0016,.00373,.00253,.00307,0.0*
1,1,.006,.00253,.00307*
20,1,.006,.00253,.00307,.0028,.00227,0.0*
1,1,.006,.0028,.00227*
20,1,.006,.0028,.00227,.00267,.00147,0.0*
1,1,.006,.00267,.00147*
20,1,.006,.00267,.00147,.00213,.0008,0.0*
1,1,.006,.00213,.0008*
20,1,.006,.00213,.0008,-.00053,-.00053,0.0*
1,1,.006,-.00053,-.00053*
20,1,.006,-.00053,-.00053,-.00173,-.00147,0.0*
1,1,.006,-.00173,-.00147*
20,1,.006,-.00173,-.00147,-.00253,-.0028,0.0*
1,1,.006,-.00253,-.0028*
20,1,.006,-.00253,-.0028,-.0028,-.004,0.0*
1,1,.006,-.0028,-.004*
20,1,.006,-.0028,-.004,.0028,-.004,0.0*
1,1,.006,.0028,-.004*
%
%ADD12MACRO12*%
%AMMACRO10*
1,1,.006,-.05834,-.07*
20,1,.006,-.05834,-.07,0.0,.07,0.0*
1,1,.006,0.0,.07*
20,1,.006,0.0,.07,.05834,-.07,0.0*
1,1,.006,.05834,-.07*
1,1,.006,.03733,-.021*
20,1,.006,.03733,-.021,-.03734,-.021,0.0*
1,1,.006,-.03734,-.021*
%
%ADD10MACRO10*%
%AMMACRO11*
1,1,.006,.01893,.00473*
20,1,.006,.01893,.00473,.0284,.01183,0.0*
1,1,.006,.0284,.01183*
20,1,.006,.0284,.01183,.0355,.02366,0.0*
1,1,.006,.0355,.02366*
20,1,.006,.0355,.02366,.04024,.04024,0.0*
1,1,.006,.04024,.04024*
20,1,.006,.04024,.04024,.0355,.05443,0.0*
1,1,.006,.0355,.05443*
20,1,.006,.0355,.05443,.02603,.0639,0.0*
1,1,.006,.02603,.0639*
20,1,.006,.02603,.0639,.00947,.071,0.0*
1,1,.006,.00947,.071*
20,1,.006,.00947,.071,-.05443,.071,0.0*
1,1,.006,-.05443,.071*
20,1,.006,-.05443,.071,-.05443,-.071,0.0*
1,1,.006,-.05443,-.071*
20,1,.006,-.05443,-.071,.02367,-.071,0.0*
1,1,.006,.02367,-.071*
20,1,.006,.02367,-.071,.04024,-.06154,0.0*
1,1,.006,.04024,-.06154*
20,1,.006,.04024,-.06154,.0497,-.04733,0.0*
1,1,.006,.0497,-.04733*
20,1,.006,.0497,-.04733,.05443,-.03077,0.0*
1,1,.006,.05443,-.03077*
20,1,.006,.05443,-.03077,.0497,-.0142,0.0*
1,1,.006,.0497,-.0142*
20,1,.006,.0497,-.0142,.0355,0.0,0.0*
1,1,.006,.0355,0.0*
20,1,.006,.0355,0.0,.01893,.00473,0.0*
1,1,.006,.01893,.00473*
20,1,.006,.01893,.00473,-.05443,.00473,0.0*
1,1,.006,-.05443,.00473*
%
%ADD11MACRO11*%
%AMMACRO17*
1,1,.006,.069,0.0*
20,1,.006,.069,0.0,0.0,-.069,0.0*
1,1,.006,0.0,-.069*
20,1,.006,0.0,-.069,-.069,0.0,0.0*
1,1,.006,-.069,0.0*
20,1,.006,-.069,0.0,0.0,.069,0.0*
1,1,.006,0.0,.069*
20,1,.006,0.0,.069,.069,0.0,0.0*
1,1,.006,.069,0.0*
1,1,.006,-.02185,-.00575*
20,1,.006,-.02185,-.00575,-.0138,.0023,0.0*
1,1,.006,-.0138,.0023*
20,1,.006,-.0138,.0023,-.0069,.0069,0.0*
1,1,.006,-.0069,.0069*
20,1,.006,-.0069,.0069,.0023,.0092,0.0*
1,1,.006,.0023,.0092*
20,1,.006,.0023,.0092,.01035,.0069,0.0*
1,1,.006,.01035,.0069*
20,1,.006,.01035,.0069,.0161,.0023,0.0*
1,1,.006,.0161,.0023*
20,1,.006,.0161,.0023,.0207,-.0046,0.0*
1,1,.006,.0207,-.0046*
20,1,.006,.0207,-.0046,.02185,-.01265,0.0*
1,1,.006,.02185,-.01265*
20,1,.006,.02185,-.01265,.0207,-.01955,0.0*
1,1,.006,.0207,-.01955*
20,1,.006,.0207,-.01955,.0161,-.02645,0.0*
1,1,.006,.0161,-.02645*
20,1,.006,.0161,-.02645,.0092,-.0322,0.0*
1,1,.006,.0092,-.0322*
20,1,.006,.0092,-.0322,.00115,-.0345,0.0*
1,1,.006,.00115,-.0345*
20,1,.006,.00115,-.0345,-.00805,-.0322,0.0*
1,1,.006,-.00805,-.0322*
20,1,.006,-.00805,-.0322,-.0161,-.0253,0.0*
1,1,.006,-.0161,-.0253*
20,1,.006,-.0161,-.0253,-.0207,-.01495,0.0*
1,1,.006,-.0207,-.01495*
20,1,.006,-.0207,-.01495,-.02185,-.00345,0.0*
1,1,.006,-.02185,-.00345*
20,1,.006,-.02185,-.00345,-.01955,.0115,0.0*
1,1,.006,-.01955,.0115*
20,1,.006,-.01955,.0115,-.0161,.01955,0.0*
1,1,.006,-.0161,.01955*
20,1,.006,-.0161,.01955,-.01035,.0276,0.0*
1,1,.006,-.01035,.0276*
20,1,.006,-.01035,.0276,-.0023,.03335,0.0*
1,1,.006,-.0023,.03335*
20,1,.006,-.0023,.03335,.00575,.0345,0.0*
1,1,.006,.00575,.0345*
20,1,.006,.00575,.0345,.0138,.0322,0.0*
1,1,.006,.0138,.0322*
20,1,.006,.0138,.0322,.01955,.02645,0.0*
1,1,.006,.01955,.02645*
%
%ADD17MACRO17*%
%AMMACRO18*
1,1,.006,.0575,.0575*
20,1,.006,.0575,.0575,.0575,-.0575,0.0*
1,1,.006,.0575,-.0575*
20,1,.006,.0575,-.0575,-.0575,-.0575,0.0*
1,1,.006,-.0575,-.0575*
20,1,.006,-.0575,-.0575,-.0575,.0575,0.0*
1,1,.006,-.0575,.0575*
20,1,.006,-.0575,.0575,.0575,.0575,0.0*
1,1,.006,.0575,.0575*
1,1,.006,-.02875,-.02875*
20,1,.006,-.02875,-.02875,-.02875,.02875,0.0*
1,1,.006,-.02875,.02875*
20,1,.006,-.02875,.02875,-.04025,.01725,0.0*
1,1,.006,-.04025,.01725*
1,1,.006,-.04025,-.02875*
20,1,.006,-.04025,-.02875,-.01725,-.02875,0.0*
1,1,.006,-.01725,-.02875*
1,1,.006,.02876,.02875*
20,1,.006,.02876,.02875,.02109,.02683,0.0*
1,1,.006,.02109,.02683*
20,1,.006,.02109,.02683,.01534,.02204,0.0*
1,1,.006,.01534,.02204*
20,1,.006,.01534,.02204,.01151,.01629,0.0*
1,1,.006,.01151,.01629*
20,1,.006,.01151,.01629,.00863,.00862,0.0*
1,1,.006,.00863,.00862*
20,1,.006,.00863,.00862,.00768,0.0,0.0*
1,1,.006,.00768,0.0*
20,1,.006,.00768,0.0,.00863,-.00863,0.0*
1,1,.006,.00863,-.00863*
20,1,.006,.00863,-.00863,.01151,-.01629,0.0*
1,1,.006,.01151,-.01629*
20,1,.006,.01151,-.01629,.01534,-.02204,0.0*
1,1,.006,.01534,-.02204*
20,1,.006,.01534,-.02204,.02109,-.02683,0.0*
1,1,.006,.02109,-.02683*
20,1,.006,.02109,-.02683,.02876,-.02875,0.0*
1,1,.006,.02876,-.02875*
20,1,.006,.02876,-.02875,.03643,-.02683,0.0*
1,1,.006,.03643,-.02683*
20,1,.006,.03643,-.02683,.04218,-.02204,0.0*
1,1,.006,.04218,-.02204*
20,1,.006,.04218,-.02204,.04601,-.01629,0.0*
1,1,.006,.04601,-.01629*
20,1,.006,.04601,-.01629,.04889,-.00863,0.0*
1,1,.006,.04889,-.00863*
20,1,.006,.04889,-.00863,.04984,0.0,0.0*
1,1,.006,.04984,0.0*
20,1,.006,.04984,0.0,.04889,.00862,0.0*
1,1,.006,.04889,.00862*
20,1,.006,.04889,.00862,.04601,.01629,0.0*
1,1,.006,.04601,.01629*
20,1,.006,.04601,.01629,.04218,.02204,0.0*
1,1,.006,.04218,.02204*
20,1,.006,.04218,.02204,.03643,.02683,0.0*
1,1,.006,.03643,.02683*
20,1,.006,.03643,.02683,.02876,.02875,0.0*
1,1,.006,.02876,.02875*
%
%ADD18MACRO18*%
%AMMACRO19*
1,1,.006,.063,0.0*
20,1,.006,.063,0.0,.062043,-.01094,0.0*
1,1,.006,.062043,-.01094*
20,1,.006,.062043,-.01094,.059201,-.021547,0.0*
1,1,.006,.059201,-.021547*
20,1,.006,.059201,-.021547,.05456,-.0315,0.0*
1,1,.006,.05456,-.0315*
20,1,.006,.05456,-.0315,.048261,-.040496,0.0*
1,1,.006,.048261,-.040496*
20,1,.006,.048261,-.040496,.040496,-.048261,0.0*
1,1,.006,.040496,-.048261*
20,1,.006,.040496,-.048261,.0315,-.05456,0.0*
1,1,.006,.0315,-.05456*
20,1,.006,.0315,-.05456,.021547,-.059201,0.0*
1,1,.006,.021547,-.059201*
20,1,.006,.021547,-.059201,.01094,-.062043,0.0*
1,1,.006,.01094,-.062043*
20,1,.006,.01094,-.062043,0.0,-.063,0.0*
1,1,.006,0.0,-.063*
20,1,.006,0.0,-.063,-.01094,-.062043,0.0*
1,1,.006,-.01094,-.062043*
20,1,.006,-.01094,-.062043,-.021547,-.059201,0.0*
1,1,.006,-.021547,-.059201*
20,1,.006,-.021547,-.059201,-.0315,-.05456,0.0*
1,1,.006,-.0315,-.05456*
20,1,.006,-.0315,-.05456,-.040496,-.048261,0.0*
1,1,.006,-.040496,-.048261*
20,1,.006,-.040496,-.048261,-.048261,-.040496,0.0*
1,1,.006,-.048261,-.040496*
20,1,.006,-.048261,-.040496,-.05456,-.0315,0.0*
1,1,.006,-.05456,-.0315*
20,1,.006,-.05456,-.0315,-.059201,-.021547,0.0*
1,1,.006,-.059201,-.021547*
20,1,.006,-.059201,-.021547,-.062043,-.01094,0.0*
1,1,.006,-.062043,-.01094*
20,1,.006,-.062043,-.01094,-.063,0.0,0.0*
1,1,.006,-.063,0.0*
20,1,.006,-.063,0.0,-.062043,.01094,0.0*
1,1,.006,-.062043,.01094*
20,1,.006,-.062043,.01094,-.059201,.021547,0.0*
1,1,.006,-.059201,.021547*
20,1,.006,-.059201,.021547,-.05456,.0315,0.0*
1,1,.006,-.05456,.0315*
20,1,.006,-.05456,.0315,-.048261,.040496,0.0*
1,1,.006,-.048261,.040496*
20,1,.006,-.048261,.040496,-.040496,.048261,0.0*
1,1,.006,-.040496,.048261*
20,1,.006,-.040496,.048261,-.0315,.05456,0.0*
1,1,.006,-.0315,.05456*
20,1,.006,-.0315,.05456,-.021547,.059201,0.0*
1,1,.006,-.021547,.059201*
20,1,.006,-.021547,.059201,-.01094,.062043,0.0*
1,1,.006,-.01094,.062043*
20,1,.006,-.01094,.062043,0.0,.063,0.0*
1,1,.006,0.0,.063*
20,1,.006,0.0,.063,.01094,.062043,0.0*
1,1,.006,.01094,.062043*
20,1,.006,.01094,.062043,.021547,.059201,0.0*
1,1,.006,.021547,.059201*
20,1,.006,.021547,.059201,.0315,.05456,0.0*
1,1,.006,.0315,.05456*
20,1,.006,.0315,.05456,.040496,.048261,0.0*
1,1,.006,.040496,.048261*
20,1,.006,.040496,.048261,.048261,.040496,0.0*
1,1,.006,.048261,.040496*
20,1,.006,.048261,.040496,.05456,.0315,0.0*
1,1,.006,.05456,.0315*
20,1,.006,.05456,.0315,.059201,.021547,0.0*
1,1,.006,.059201,.021547*
20,1,.006,.059201,.021547,.062043,.01094,0.0*
1,1,.006,.062043,.01094*
20,1,.006,.062043,.01094,.063,0.0,0.0*
1,1,.006,.063,0.0*
1,1,.006,-.0315,-.0315*
20,1,.006,-.0315,-.0315,-.0315,.0315,0.0*
1,1,.006,-.0315,.0315*
20,1,.006,-.0315,.0315,-.0441,.0189,0.0*
1,1,.006,-.0441,.0189*
1,1,.006,-.0441,-.0315*
20,1,.006,-.0441,-.0315,-.0189,-.0315,0.0*
1,1,.006,-.0189,-.0315*
1,1,.006,.03151,-.0315*
20,1,.006,.03151,-.0315,.03151,.0315,0.0*
1,1,.006,.03151,.0315*
20,1,.006,.03151,.0315,.01891,.0189,0.0*
1,1,.006,.01891,.0189*
1,1,.006,.01891,-.0315*
20,1,.006,.01891,-.0315,.04411,-.0315,0.0*
1,1,.006,.04411,-.0315*
%
%ADD19MACRO19*%
%AMMACRO13*
1,1,.006,0.0,.02*
20,1,.006,0.0,.02,-.017321,.01,0.0*
1,1,.006,-.017321,.01*
20,1,.006,-.017321,.01,-.017321,-.01,0.0*
1,1,.006,-.017321,-.01*
20,1,.006,-.017321,-.01,0.0,-.02,0.0*
1,1,.006,0.0,-.02*
20,1,.006,0.0,-.02,.017321,-.01,0.0*
1,1,.006,.017321,-.01*
20,1,.006,.017321,-.01,.017321,.01,0.0*
1,1,.006,.017321,.01*
20,1,.006,.017321,.01,0.0,.02,0.0*
1,1,.006,0.0,.02*
1,1,.006,.004,-.01*
20,1,.006,.004,-.01,.004,.01,0.0*
1,1,.006,.004,.01*
20,1,.006,.004,.01,-.00833,-.00433,0.0*
1,1,.006,-.00833,-.00433*
20,1,.006,-.00833,-.00433,.00833,-.00433,0.0*
1,1,.006,.00833,-.00433*
%
%ADD13MACRO13*%
%AMMACRO15*
1,1,.006,.0175,0.0*
20,1,.006,.0175,0.0,.00875,.015155,0.0*
1,1,.006,.00875,.015155*
20,1,.006,.00875,.015155,-.00875,.015155,0.0*
1,1,.006,-.00875,.015155*
20,1,.006,-.00875,.015155,-.0175,0.0,0.0*
1,1,.006,-.0175,0.0*
20,1,.006,-.0175,0.0,-.00875,-.015155,0.0*
1,1,.006,-.00875,-.015155*
20,1,.006,-.00875,-.015155,.00875,-.015155,0.0*
1,1,.006,.00875,-.015155*
20,1,.006,.00875,-.015155,.0175,0.0,0.0*
1,1,.006,.0175,0.0*
1,1,.006,-.00642,-.00525*
20,1,.006,-.00642,-.00525,-.00467,-.00729,0.0*
1,1,.006,-.00467,-.00729*
20,1,.006,-.00467,-.00729,-.00233,-.00846,0.0*
1,1,.006,-.00233,-.00846*
20,1,.006,-.00233,-.00846,.00029,-.00875,0.0*
1,1,.006,.00029,-.00875*
20,1,.006,.00029,-.00875,.00263,-.00846,0.0*
1,1,.006,.00263,-.00846*
20,1,.006,.00263,-.00846,.00496,-.007,0.0*
1,1,.006,.00496,-.007*
20,1,.006,.00496,-.007,.00642,-.00525,0.0*
1,1,.006,.00642,-.00525*
20,1,.006,.00642,-.00525,.00671,-.0035,0.0*
1,1,.006,.00671,-.0035*
20,1,.006,.00671,-.0035,.00613,-.00146,0.0*
1,1,.006,.00613,-.00146*
20,1,.006,.00613,-.00146,.00408,0.0,0.0*
1,1,.006,.00408,0.0*
20,1,.006,.00408,0.0,.00204,.00058,0.0*
1,1,.006,.00204,.00058*
20,1,.006,.00204,.00058,-.00058,.00058,0.0*
1,1,.006,-.00058,.00058*
1,1,.006,.00204,.00058*
20,1,.006,.00204,.00058,.00379,.00146,0.0*
1,1,.006,.00379,.00146*
20,1,.006,.00379,.00146,.00525,.00292,0.0*
1,1,.006,.00525,.00292*
20,1,.006,.00525,.00292,.00583,.00467,0.0*
1,1,.006,.00583,.00467*
20,1,.006,.00583,.00467,.00525,.00642,0.0*
1,1,.006,.00525,.00642*
20,1,.006,.00525,.00642,.00379,.00787,0.0*
1,1,.006,.00379,.00787*
20,1,.006,.00379,.00787,.00117,.00875,0.0*
1,1,.006,.00117,.00875*
20,1,.006,.00117,.00875,-.00146,.00846,0.0*
1,1,.006,-.00146,.00846*
20,1,.006,-.00146,.00846,-.00408,.00729,0.0*
1,1,.006,-.00408,.00729*
%
%ADD15MACRO15*%
%AMMACRO14*
1,1,.006,0.0,.079*
20,1,.006,0.0,.079,.079,-.079,0.0*
1,1,.006,.079,-.079*
20,1,.006,.079,-.079,-.079,-.079,0.0*
1,1,.006,-.079,-.079*
20,1,.006,-.079,-.079,0.0,.079,0.0*
1,1,.006,0.0,.079*
1,1,.006,-.00263,-.0395*
20,1,.006,-.00263,-.0395,0.0,-.02238,0.0*
1,1,.006,0.0,-.02238*
20,1,.006,0.0,-.02238,.00395,-.0079,0.0*
1,1,.006,.00395,-.0079*
20,1,.006,.00395,-.0079,.00922,.00527,0.0*
1,1,.006,.00922,.00527*
20,1,.006,.00922,.00527,.0158,.01975,0.0*
1,1,.006,.0158,.01975*
20,1,.006,.0158,.01975,.02633,.0395,0.0*
1,1,.006,.02633,.0395*
20,1,.006,.02633,.0395,-.02633,.0395,0.0*
1,1,.006,-.02633,.0395*
%
%ADD14MACRO14*%
%ADD23C,.02*%
%ADD24C,.006*%
G75*
%LPD*%
G75*
G54D10*
X-222440Y19685D03*
Y1948818D03*
X643700Y19685D03*
Y1948818D03*
X897450Y1514825D03*
G54D11*
X29921Y24803D03*
Y111417D03*
Y458031D03*
Y544646D03*
Y717874D03*
Y804488D03*
X30000Y1164000D03*
X29921Y1250630D03*
Y1423858D03*
Y1510472D03*
Y1857086D03*
Y1943701D03*
X897450Y1484975D03*
G54D20*
X80709Y139409D03*
Y309409D03*
X149606Y139409D03*
Y309409D03*
X897450Y1604375D03*
G54D12*
X8594Y6500D03*
X20000Y6000D03*
X17000Y36500D03*
X5594Y87000D03*
Y53500D03*
X29500Y53000D03*
X26000Y87000D03*
X30800Y130300D03*
X4594Y120500D03*
X23500Y124000D03*
X15000Y131500D03*
X14500Y100500D03*
Y112500D03*
X4500Y105500D03*
X5000Y137500D03*
X22500Y190000D03*
X29700Y191400D03*
X5594Y153500D03*
X4594Y187500D03*
X16500Y175000D03*
X15500Y143500D03*
X27000Y182000D03*
X14000Y184000D03*
X4500Y170500D03*
X21500Y241500D03*
X4594Y234000D03*
X24000Y212000D03*
X29000Y200500D03*
X13500Y230500D03*
X13000Y212500D03*
X5000Y221000D03*
X12500Y197500D03*
X4500Y202500D03*
X28050Y256950D03*
X5094Y278000D03*
X6094Y257000D03*
X13500Y279000D03*
X13000Y244000D03*
X12500Y266500D03*
X5500Y269500D03*
X5000Y247500D03*
X19721Y267203D03*
X5594Y312000D03*
X5304Y342500D03*
X4900Y328000D03*
X13500Y303500D03*
X13000Y321000D03*
X13500Y295000D03*
X5500Y295500D03*
X6500Y375000D03*
X27000Y371000D03*
X4800Y356200D03*
X23700Y363900D03*
X29500Y364500D03*
X27000Y377500D03*
Y384000D03*
Y389500D03*
X4594Y421000D03*
X5304Y444500D03*
Y440500D03*
X5000Y408500D03*
X5304Y434500D03*
X4594Y396500D03*
X26500Y440000D03*
X26000Y432500D03*
X23800Y410700D03*
X5094Y469500D03*
X5000Y495000D03*
X4700Y458200D03*
X5000Y486500D03*
X5094Y600000D03*
X13510Y597990D03*
X14000Y614000D03*
X4594Y625000D03*
X18000Y608000D03*
X6000Y612000D03*
Y646000D03*
X26000Y656500D03*
X5594Y688500D03*
X5304Y661000D03*
X14000Y659000D03*
X23000Y677500D03*
X8000Y678000D03*
X31000Y700500D03*
X20000Y696000D03*
X6000Y698000D03*
X28000Y706000D03*
X31000Y747000D03*
X22000Y746000D03*
X27000Y750000D03*
X26000Y732000D03*
X18000Y724000D03*
Y732500D03*
Y712000D03*
X6000Y706500D03*
Y722000D03*
Y730500D03*
X5594Y778000D03*
X6500Y799000D03*
X9500Y804000D03*
X24000Y756000D03*
X30000Y782000D03*
X16100Y794600D03*
X5594Y844500D03*
X6094Y819500D03*
X30500D03*
X10000Y811500D03*
X24000Y846000D03*
X24500Y853500D03*
X16000Y828000D03*
Y814000D03*
Y856000D03*
Y842000D03*
X4500Y833500D03*
X26053Y828247D03*
X5094Y897500D03*
X5594Y869000D03*
X16000Y906000D03*
X18000Y884000D03*
Y870000D03*
X4500Y857500D03*
X5000Y883500D03*
X18500Y896500D03*
X23053Y861247D03*
X5304Y926000D03*
X4594Y954000D03*
X18000Y934000D03*
Y920000D03*
X16000Y948000D03*
X4500Y913000D03*
Y941500D03*
X26053Y938247D03*
X5594Y984500D03*
X28000Y992000D03*
X16000Y962000D03*
Y990000D03*
Y976000D03*
Y1000000D03*
X4500Y970000D03*
Y997000D03*
X25053Y971247D03*
X4594Y1041500D03*
Y1013500D03*
X6000Y1058000D03*
X26000Y1010000D03*
X16000Y1014000D03*
Y1046000D03*
Y1032000D03*
X14000Y1060000D03*
X4500Y1029500D03*
X27553Y1029247D03*
X5094Y1074500D03*
X28000Y1072000D03*
X14000Y1074000D03*
Y1100000D03*
Y1086000D03*
X16000Y1110000D03*
X6000Y1096000D03*
X26100Y1088600D03*
X27218Y1097000D03*
X16000Y1124000D03*
Y1148000D03*
Y1134000D03*
Y1162000D03*
X6000Y1138000D03*
Y1118000D03*
Y1152000D03*
X26600Y1132400D03*
X24553Y1153247D03*
X5304Y1208000D03*
X4594Y1169500D03*
X24000Y1180000D03*
X16000Y1176000D03*
X8500Y1237000D03*
X30000Y1240000D03*
X16000Y1262000D03*
Y1244000D03*
X6000Y1252000D03*
X22000Y1232000D03*
X6500Y1302000D03*
X5094Y1268500D03*
X17700Y1283000D03*
X12000Y1274000D03*
Y1294000D03*
X28000Y1266000D03*
Y1286000D03*
Y1300000D03*
X19800Y1315400D03*
X13500Y1365000D03*
X6000Y1318000D03*
X28000Y1320000D03*
X30800Y1403900D03*
X5304Y1409400D03*
X4594Y1382000D03*
X7500Y1376500D03*
X8000Y1368000D03*
X4800Y1460700D03*
X4594Y1435500D03*
X5304Y1504100D03*
X4600Y1484800D03*
X29500Y1495800D03*
X5304Y1540500D03*
Y1522100D03*
X26600Y1570100D03*
X26900Y1547900D03*
Y1559100D03*
X4594Y1607500D03*
X5304Y1576200D03*
X26700Y1579800D03*
X7500Y1640200D03*
X5304Y1659000D03*
X4594Y1632000D03*
X29000Y1671000D03*
X19250Y1663100D03*
X13900Y1706200D03*
X5304Y1723500D03*
X4900Y1708000D03*
X4594Y1691000D03*
X4700Y1676100D03*
X30000Y1731000D03*
X4594Y1775000D03*
Y1751000D03*
X12600Y1753800D03*
X13100Y1742600D03*
Y1728900D03*
X12900Y1765200D03*
X4594Y1826500D03*
X5900Y1814100D03*
X4594Y1799500D03*
X12600Y1792800D03*
X12500Y1782500D03*
X4594Y1878500D03*
X12800Y1863700D03*
X5000Y1864100D03*
X18600Y1871400D03*
X4594Y1850000D03*
X24200Y1836700D03*
X15000Y1854900D03*
X14500Y1842000D03*
X27500Y1874500D03*
X24800Y1926500D03*
X5094Y1921000D03*
X4594Y1902000D03*
X24500Y1884000D03*
X13100Y1933900D03*
X16100Y1950700D03*
X5094Y1944500D03*
X15500Y1942500D03*
X4500Y1936000D03*
X6500Y1962000D03*
X25000Y1962500D03*
X12500Y1959000D03*
X63594Y7000D03*
Y25500D03*
X40594Y6000D03*
X49000Y18500D03*
X43000Y27000D03*
X64000Y17000D03*
X53000Y5000D03*
X31500Y5500D03*
X51500Y53000D03*
X74000Y45000D03*
X64500Y40000D03*
X32000D03*
X63098Y119103D03*
X52000Y115600D03*
X51700Y131700D03*
X34400Y95300D03*
X71000Y131859D03*
X37000Y124000D03*
X62598Y141103D03*
X51900Y145700D03*
X69000Y153000D03*
X73500Y146000D03*
X60800Y147700D03*
X68000Y286000D03*
Y296000D03*
Y320000D03*
Y312000D03*
X76000Y296000D03*
X68000Y304000D03*
X74000Y390000D03*
X66000D03*
X58000D03*
X64000Y446500D03*
X74000Y408000D03*
X66000D03*
Y418000D03*
X74000D03*
X73700Y423000D03*
X66000Y426000D03*
X58000D03*
X74000Y400000D03*
X66000D03*
X58000D03*
Y408000D03*
Y417500D03*
X58100Y431900D03*
X63096Y434540D03*
X68500Y434300D03*
X81000Y410500D03*
X82000Y483600D03*
X46000Y490500D03*
X50100Y493000D03*
X42500D03*
X78200Y481700D03*
X63300Y464400D03*
X64000Y451000D03*
Y455500D03*
Y460000D03*
X62500Y472900D03*
X62600Y468500D03*
X62500Y477000D03*
X78500Y506700D03*
X78200Y501000D03*
X71800Y506900D03*
X71900Y501000D03*
X72100Y521800D03*
X79400D03*
X72000Y514800D03*
X78000D03*
X51700Y522500D03*
X74942Y530983D03*
X72500Y595900D03*
X56800Y576950D03*
X34100Y566600D03*
X36000Y554000D03*
X79122Y565700D03*
X79458Y578758D03*
X69800Y574200D03*
X80900Y668400D03*
X56710Y681069D03*
X40000Y659000D03*
X43281Y674991D03*
X39096Y674917D03*
X69100Y698006D03*
X71800Y701300D03*
X74100Y669398D03*
X32000Y666000D03*
X50000Y712500D03*
Y749000D03*
X40000Y746500D03*
X36000Y730000D03*
X46000Y726000D03*
X44000Y782000D03*
X42000Y802000D03*
Y788000D03*
X47600Y796800D03*
X81500Y837500D03*
X82000Y806500D03*
X48000Y816000D03*
X38000Y834000D03*
Y820000D03*
X46000Y848000D03*
Y834000D03*
X32000Y844000D03*
X78300Y832600D03*
X77600Y849100D03*
X48100Y853400D03*
X45600Y827500D03*
X37500Y907500D03*
X77000Y871500D03*
X79000Y857000D03*
X62500Y862000D03*
X61500Y876500D03*
X78000Y878500D03*
X32000Y858000D03*
Y886000D03*
Y872000D03*
X77500Y907000D03*
X78300Y893900D03*
X77000Y863000D03*
X47000Y877600D03*
X40900Y901500D03*
X41000Y931899D03*
X37500Y912000D03*
X34000Y944000D03*
Y934500D03*
X33500Y953000D03*
X61500Y938500D03*
X81500Y940000D03*
X75500Y936500D03*
X69500Y939000D03*
X55500Y955500D03*
X56500Y940000D03*
X62500Y924500D03*
X70000Y914500D03*
Y925500D03*
X76500Y927000D03*
X77500Y917000D03*
X64000Y980500D03*
X33500Y962500D03*
X34000Y984000D03*
Y974500D03*
Y1008000D03*
X55500Y968000D03*
X76400Y999100D03*
X37700Y991600D03*
X31600Y1024300D03*
X33600Y1029900D03*
X34000Y1017500D03*
X39300Y1105800D03*
X34000Y1102000D03*
Y1072000D03*
X33550Y1080100D03*
X67302Y1133490D03*
X78292Y1148041D03*
X66000Y1149500D03*
X79044Y1144112D03*
X37500Y1118900D03*
X74000Y1132000D03*
X34000Y1144000D03*
X40000Y1136000D03*
Y1156000D03*
X32000Y1114000D03*
X77293Y1129729D03*
X64500Y1165700D03*
X58000Y1206000D03*
X60000Y1194000D03*
X61000Y1173000D03*
X54000Y1184000D03*
X44000Y1194000D03*
X42000Y1242000D03*
X50000Y1244000D03*
X58000Y1250000D03*
X46000Y1218000D03*
X31500Y1222000D03*
X58000D03*
X39500Y1231000D03*
X51800Y1231600D03*
X50100Y1261500D03*
X42000Y1266000D03*
Y1290000D03*
X34000Y1312000D03*
X40000Y1278000D03*
Y1298000D03*
X44000Y1306000D03*
X58000Y1312000D03*
Y1292000D03*
Y1272000D03*
X52000Y1296300D03*
X61000Y1363500D03*
X38000Y1334000D03*
X50000Y1318000D03*
X44000Y1326000D03*
Y1340000D03*
X54000Y1330000D03*
X72000Y1360000D03*
X31500Y1397500D03*
X81500Y1382000D03*
Y1416500D03*
Y1404000D03*
X52500Y1368500D03*
X71800Y1373900D03*
X70500Y1378500D03*
X69400Y1402900D03*
X39500Y1407900D03*
X55600Y1381700D03*
X48900Y1390500D03*
X60900D03*
X56700Y1400100D03*
X68800Y1417800D03*
X58800Y1412400D03*
X49000Y1413300D03*
X72900Y1393600D03*
X74900Y1408800D03*
X32000Y1391500D03*
X61500Y1380000D03*
X70400Y1444500D03*
X79000Y1436400D03*
X76200Y1430700D03*
X60600Y1423600D03*
X75600Y1420300D03*
X66500Y1433500D03*
X53100Y1430700D03*
X42600Y1444200D03*
X34000Y1465900D03*
X49100Y1448400D03*
X68500Y1454600D03*
X74500Y1461800D03*
X72300Y1469800D03*
X59000Y1444500D03*
X77000Y1449000D03*
X58100Y1459300D03*
X53500Y1519000D03*
X72000Y1514000D03*
X58500Y1519000D03*
X63000Y1482300D03*
X42700Y1500000D03*
X72700Y1480500D03*
X46500Y1484900D03*
X64100Y1495400D03*
X73000Y1491200D03*
X43300Y1518500D03*
X49500Y1505000D03*
X59000Y1472000D03*
X34000Y1477600D03*
X57000Y1568500D03*
X57500Y1562000D03*
X59500Y1541000D03*
X54300Y1541200D03*
X80000Y1531600D03*
X73900Y1535900D03*
X46600Y1541100D03*
X45300Y1563600D03*
X45900Y1532800D03*
X45400Y1523800D03*
X37900Y1570000D03*
X38800Y1541700D03*
X38300Y1561800D03*
X54500Y1574000D03*
X44400Y1592100D03*
X33100Y1587400D03*
X38300Y1579600D03*
X71600Y1607700D03*
X50600Y1589300D03*
Y1582800D03*
Y1595300D03*
Y1601300D03*
X55300Y1601100D03*
Y1595100D03*
Y1582600D03*
Y1589100D03*
X68700Y1603900D03*
X55400Y1613300D03*
X58500Y1607700D03*
X43200Y1634800D03*
X59500Y1667000D03*
X70000Y1668000D03*
X76000Y1646000D03*
Y1634000D03*
X75500Y1659500D03*
X54000Y1646500D03*
X64500Y1646000D03*
X55000Y1634000D03*
X64000D03*
X64500Y1658500D03*
X53500Y1659000D03*
X42500Y1699500D03*
X44600Y1724400D03*
X44900Y1706800D03*
X56000Y1695000D03*
Y1704500D03*
Y1712500D03*
X55500Y1723500D03*
X69000Y1684500D03*
X80500D03*
X62500Y1691500D03*
X65000Y1724000D03*
X62500Y1709000D03*
X72500Y1717000D03*
Y1699000D03*
X75500Y1679000D03*
X62500Y1700000D03*
X38800Y1775000D03*
X41600Y1746900D03*
X48400D03*
X53000Y1750500D03*
X36700Y1764700D03*
X56500Y1769300D03*
X44900Y1740300D03*
X64500Y1758500D03*
X55500Y1735500D03*
X65000Y1735000D03*
X79000Y1766500D03*
X65000Y1749000D03*
Y1768000D03*
Y1742500D03*
X71500Y1760000D03*
X72500Y1733000D03*
X60000Y1730000D03*
X42000Y1784400D03*
X44400Y1821400D03*
X81000Y1802000D03*
X73000Y1813000D03*
X64500Y1821500D03*
Y1812000D03*
Y1801500D03*
X65000Y1790000D03*
X72000Y1798000D03*
X39179Y1792306D03*
X39700Y1869700D03*
X46700Y1857700D03*
X46500Y1850200D03*
X44500Y1833500D03*
X39700Y1846600D03*
X45500Y1865000D03*
X31500Y1878500D03*
X36000Y1835500D03*
X75500Y1838500D03*
X63500Y1863000D03*
Y1856000D03*
X64000Y1844500D03*
Y1834000D03*
X73000Y1847000D03*
X72500Y1830000D03*
X54500Y1889500D03*
X63500Y1928000D03*
X61500Y1922500D03*
X46000Y1923000D03*
X54000Y1928500D03*
X35300Y1925300D03*
X36500Y1900500D03*
X63500Y1963000D03*
X63594Y1935500D03*
X61600Y1954700D03*
X34500Y1963200D03*
X41100Y1957500D03*
X55300Y1959100D03*
X45100Y1933400D03*
X35000Y1933500D03*
X43500Y1945000D03*
X49053Y1951747D03*
X128500Y89000D03*
X118000Y54500D03*
X124000Y74500D03*
X105000Y55000D03*
X85000Y45000D03*
X105000D03*
X95000D03*
X115000D03*
X125000D03*
X127700Y119200D03*
X128700Y104200D03*
X131000Y138100D03*
X118000Y124500D03*
X119000Y109500D03*
X95000Y125000D03*
X105000D03*
X95000Y134000D03*
X86000Y152000D03*
X129000Y160100D03*
X131000Y150100D03*
X118000Y154500D03*
Y142500D03*
X95000Y143000D03*
X105000D03*
X95000Y155000D03*
X105000D03*
X131800Y289700D03*
X130900Y259100D03*
X102000Y312000D03*
X104000Y304000D03*
X94000D03*
Y312000D03*
Y320000D03*
X114000Y296000D03*
X106000D03*
X96000D03*
X86000D03*
X111500Y390000D03*
X101300Y390100D03*
X105500Y390000D03*
X118000Y396000D03*
Y386000D03*
X105500Y406500D03*
X101500D03*
X107000Y426500D03*
X98000D03*
X102500D03*
X111200Y426400D03*
X110500Y406500D03*
X89800Y446000D03*
X131000Y447000D03*
X91900Y410500D03*
X84500Y433000D03*
X88500Y426500D03*
X86400Y410500D03*
X118000Y424000D03*
Y404000D03*
X130000Y432000D03*
X118000Y414000D03*
X129000Y485500D03*
X120000D03*
X110800Y482600D03*
X99800Y482000D03*
X110800Y488600D03*
X100000Y488000D03*
Y494000D03*
X110800Y494600D03*
X129000Y493500D03*
X120000D03*
X122500Y450500D03*
Y457500D03*
Y463500D03*
X121500Y475500D03*
X122500Y469500D03*
X117000Y455000D03*
Y460500D03*
Y466000D03*
Y471500D03*
Y449000D03*
X89800Y452900D03*
Y459000D03*
X111500Y473000D03*
X99500D03*
X89800Y464800D03*
X130500Y454000D03*
Y461000D03*
Y468000D03*
Y474500D03*
X120000Y501500D03*
X129000Y517500D03*
X100000Y512000D03*
X110800Y500600D03*
X100000Y500000D03*
X85000Y506400D03*
X84500Y514400D03*
X129000Y501500D03*
Y509500D03*
X110800Y512600D03*
X120000Y517500D03*
X100000Y506000D03*
X110800Y506600D03*
X120000Y509500D03*
Y523500D03*
X129000D03*
X100000Y519100D03*
X117000Y530000D03*
X103100Y587600D03*
X87595Y581300D03*
X90630Y602020D03*
X86443Y662853D03*
X88967Y659749D03*
X84504Y666353D03*
X90674Y663367D03*
X121500Y683500D03*
X119576Y687008D03*
X120702Y690847D03*
X100600Y670600D03*
X112800Y653500D03*
X108200Y655825D03*
X119000Y673300D03*
X87310Y676796D03*
X124800Y696600D03*
X129800Y696800D03*
X98000Y674327D03*
X102913Y673973D03*
X107113Y674001D03*
X108500Y695500D03*
X103500D03*
X99001Y694866D03*
X125000Y734000D03*
X116500Y752000D03*
X125000Y751000D03*
X125500Y741500D03*
X130000Y736500D03*
X120500Y732500D03*
X120000Y717500D03*
X115000Y704500D03*
X106882Y794201D03*
X107000Y798200D03*
Y802400D03*
X123000Y800000D03*
X122500Y792500D03*
X114000Y800000D03*
X113500Y792500D03*
X130000Y800000D03*
X129500Y792500D03*
X121500Y783500D03*
X121000Y776000D03*
X129500Y782000D03*
X129000Y774500D03*
X125000Y758500D03*
X115200Y784200D03*
X115000Y773200D03*
X121000Y767900D03*
X95500Y841500D03*
X82500Y814000D03*
X123500Y842500D03*
Y816000D03*
X123000Y808500D03*
X115000Y813000D03*
X114500Y805500D03*
X129200Y830400D03*
X129800Y813500D03*
X124500Y825100D03*
X90500Y831500D03*
X87000Y839500D03*
X85500Y903000D03*
X116053Y903247D03*
X127000Y903000D03*
X90000Y893000D03*
X102500Y893500D03*
X117500Y893000D03*
X125000Y868500D03*
X124500Y858000D03*
X107000Y903000D03*
X124500Y876500D03*
X126000Y892500D03*
X96053Y903247D03*
X83400Y878600D03*
X125500Y944000D03*
X105000Y958000D03*
X86500Y932000D03*
X96500Y916500D03*
X107000Y918000D03*
X115000Y920000D03*
X125500D03*
X126000Y930000D03*
X115500D03*
X99000Y953000D03*
X88500Y940500D03*
X120000Y916000D03*
X124000Y909000D03*
X113500Y909500D03*
X103500D03*
X94000Y910500D03*
X85500Y915000D03*
X126000Y954000D03*
X110000Y949500D03*
X117529Y948844D03*
X93000Y925500D03*
X125000Y967000D03*
X130500Y966000D03*
X124000Y971500D03*
X117000Y1008500D03*
X105500Y996000D03*
X95500Y999000D03*
X87000Y997500D03*
X106500Y1008500D03*
X119000Y975000D03*
X108500Y964000D03*
Y971000D03*
X114800Y1005000D03*
X124618Y959244D03*
X97250Y1023500D03*
X110500Y1041500D03*
X111500Y1030000D03*
Y1020000D03*
X104000Y1014000D03*
X110500Y1051000D03*
X103500Y1042000D03*
Y1028500D03*
X116500Y1049000D03*
Y1035500D03*
X117500Y1023500D03*
X95400Y1064100D03*
X91400D03*
X87000Y1063000D03*
X120000Y1108000D03*
Y1102000D03*
X115000Y1108500D03*
X110500Y1064500D03*
Y1112000D03*
X103500Y1073500D03*
X104500Y1095000D03*
X116500Y1076000D03*
X109000Y1083500D03*
X116500Y1062500D03*
X89000Y1167400D03*
X118500Y1166000D03*
X105000Y1196000D03*
X119300Y1191400D03*
X119500Y1177500D03*
Y1205500D03*
X104500Y1208000D03*
X94000Y1189000D03*
X91500Y1200000D03*
X99000Y1265500D03*
X117500Y1251000D03*
X112000Y1250500D03*
Y1244500D03*
X119300Y1245400D03*
Y1219400D03*
X119500Y1231500D03*
X104500Y1219500D03*
X92000Y1254000D03*
X103500Y1229000D03*
X92000Y1241500D03*
X103000Y1244900D03*
X92000Y1214500D03*
X91500Y1229000D03*
X119000Y1269000D03*
X99500Y1310000D03*
Y1294000D03*
X98000Y1282000D03*
X123800Y1283900D03*
X124000Y1270000D03*
X113800Y1287900D03*
X114000Y1274000D03*
X123800Y1311900D03*
X124000Y1298000D03*
X92000Y1295500D03*
X91500Y1314500D03*
X114500Y1296500D03*
X97800Y1327900D03*
X123800Y1337900D03*
X124000Y1324000D03*
X113800Y1331900D03*
X114000Y1318000D03*
X115800Y1363900D03*
X116000Y1350000D03*
X123800Y1365900D03*
X124000Y1352000D03*
X83800Y1365900D03*
X84000Y1352000D03*
X93800Y1353900D03*
X94000Y1340000D03*
Y1366000D03*
X90800Y1331200D03*
X105500Y1415000D03*
X99600Y1416500D03*
X100500Y1384500D03*
Y1389000D03*
X124000Y1376500D03*
X114000Y1376000D03*
X114500Y1370500D03*
X83800Y1391900D03*
X93800Y1379900D03*
Y1393200D03*
X93600Y1407100D03*
X97500Y1412000D03*
X89700Y1409700D03*
X110000Y1418000D03*
X86900Y1451000D03*
X126600Y1461500D03*
X132200Y1424800D03*
X94000Y1427800D03*
X87200Y1431900D03*
X87700Y1446500D03*
X87300Y1436000D03*
X95500Y1468000D03*
X113024Y1452079D03*
X117122Y1448001D03*
X117195Y1456070D03*
X121338Y1452021D03*
X117024Y1452000D03*
X83500Y1469500D03*
X87200Y1440000D03*
X99800Y1455600D03*
X109500Y1438000D03*
X98500Y1428400D03*
X117000Y1435200D03*
X94000Y1514000D03*
X93000Y1518700D03*
X85200Y1515000D03*
X91300Y1488600D03*
X97000Y1503100D03*
X93500Y1482700D03*
X99170Y1485790D03*
X103700Y1470300D03*
X85000Y1490000D03*
X124500Y1524000D03*
X87900Y1523400D03*
X94000Y1562000D03*
Y1550000D03*
X119000Y1529500D03*
X129000Y1562500D03*
X128000Y1568000D03*
X114000Y1546000D03*
X129000Y1542500D03*
X122000Y1546000D03*
Y1538000D03*
X129000Y1549000D03*
X94000Y1556000D03*
X129000Y1535000D03*
X115900Y1569700D03*
X94000Y1568000D03*
X102000D03*
Y1556000D03*
Y1550000D03*
Y1562000D03*
Y1544000D03*
X114000Y1564000D03*
X121800Y1569929D03*
X122000Y1564000D03*
X114000Y1558000D03*
X122000Y1552000D03*
X114000D03*
X122000Y1558000D03*
X111500Y1537500D03*
X129000Y1555500D03*
X116000Y1576000D03*
X122000D03*
Y1584000D03*
X116000D03*
Y1592000D03*
X122000D03*
X116000Y1600000D03*
X122000Y1612000D03*
X104000Y1605500D03*
X116000Y1612000D03*
X122000Y1600000D03*
X128000Y1606000D03*
X94500Y1605500D03*
X113500D03*
X117500Y1669000D03*
X127500D03*
X86000D03*
X97000D03*
X107000D03*
X127000Y1646000D03*
X118000D03*
X117000Y1633500D03*
X127500Y1633000D03*
Y1659500D03*
X117500D03*
X108000Y1646000D03*
X106000Y1634000D03*
X107000Y1659500D03*
X96000Y1646000D03*
X96500Y1634000D03*
X97000Y1659500D03*
X86000Y1646000D03*
Y1634000D03*
Y1659500D03*
X122000Y1685500D03*
X91000Y1685000D03*
X103000D03*
X112500D03*
X98500Y1717000D03*
Y1696500D03*
X99000Y1707000D03*
X117500Y1679000D03*
X125000D03*
X86000D03*
X97500Y1679500D03*
X107500Y1679000D03*
X109500Y1719500D03*
X110000Y1709500D03*
X109500Y1699000D03*
X119500Y1710110D03*
Y1696610D03*
X86500Y1713610D03*
Y1700110D03*
X119500Y1725110D03*
X111500Y1768500D03*
X108500Y1727000D03*
X117500Y1732000D03*
X119500Y1760000D03*
X97500Y1775500D03*
X86500Y1726000D03*
X87000Y1774110D03*
X119500Y1747110D03*
X110500Y1801000D03*
X88500Y1785000D03*
X97500Y1796000D03*
X98000Y1786000D03*
X86500Y1793110D03*
X108268Y1777300D03*
X107768Y1789110D03*
X120000Y1811500D03*
X119500Y1796500D03*
X114000Y1843500D03*
X97000Y1850500D03*
X99500Y1862500D03*
X106500D03*
X114500D03*
X122500D03*
X120500Y1836500D03*
Y1850500D03*
X108500Y1851610D03*
X85100Y1844500D03*
X85700Y1852300D03*
X132000Y1892000D03*
X124500Y1892403D03*
X116948Y1892000D03*
X118000Y1922000D03*
X184000Y55500D03*
X174000D03*
X164000D03*
X154000Y75500D03*
X135000Y50000D03*
Y70000D03*
Y45000D03*
X145000D03*
X155000D03*
X165000D03*
X175000D03*
X137200Y123600D03*
X180500Y112000D03*
X167000Y130500D03*
X176000Y131000D03*
X167000Y93000D03*
X153000Y90500D03*
X171500Y105500D03*
X170500Y120500D03*
X146500Y131859D03*
X154000Y105500D03*
X147600Y150900D03*
X165300Y145200D03*
X137900Y171400D03*
X174500Y143500D03*
X173500Y151500D03*
X138800Y162100D03*
X142000Y291000D03*
X141300Y298100D03*
X143400Y318700D03*
X174000Y316000D03*
X164000D03*
X182000Y296000D03*
X172000D03*
X162000D03*
X172000Y310000D03*
X182000D03*
X184000Y303000D03*
X176000Y302000D03*
X166000D03*
X143300Y343400D03*
X151300Y298200D03*
X181800Y369000D03*
X181100Y364050D03*
X180850Y348800D03*
X150000Y386000D03*
X134000Y396000D03*
X150000D03*
X134000Y386000D03*
X161600Y445900D03*
X136000Y447000D03*
X134000Y404500D03*
X174500Y432000D03*
X162000D03*
X145500Y427000D03*
X142000Y432000D03*
X134000Y414000D03*
X150000Y404000D03*
Y414000D03*
X134000Y424000D03*
X150000D03*
X169200Y482800D03*
X144000Y493500D03*
Y486182D03*
X137000Y493000D03*
X136500Y485500D03*
X161900Y451600D03*
X162000Y457600D03*
X161900Y463300D03*
X135500Y454000D03*
Y461000D03*
Y474500D03*
Y468000D03*
X173700Y513900D03*
X144000Y517500D03*
Y501500D03*
X173500Y506000D03*
X173600Y498800D03*
X157100Y500000D03*
X137000Y510000D03*
X137500Y523500D03*
X174900Y523300D03*
X156800Y515400D03*
Y506900D03*
X137000Y501500D03*
X137500Y517500D03*
X144600Y533800D03*
X182600Y546900D03*
X180500Y595000D03*
X171600Y595400D03*
X147500Y551500D03*
X141800Y559250D03*
X150500Y596000D03*
X153500Y574359D03*
X140700Y576600D03*
X152700Y618803D03*
X170349Y619949D03*
X145500Y604000D03*
X175800Y617635D03*
X164950Y615700D03*
X180500Y627771D03*
X165600Y630269D03*
X151432Y661741D03*
X148995Y658568D03*
X134100Y674500D03*
X176000Y679000D03*
Y665500D03*
X167300Y653800D03*
X162300Y659100D03*
X183500Y698000D03*
X165500Y677500D03*
X159700Y652000D03*
X181000Y729000D03*
Y715500D03*
X182500Y745000D03*
X181500Y738500D03*
X169100Y722100D03*
X169000Y795500D03*
X178000Y797500D03*
X175000Y786500D03*
X182500Y758500D03*
X173500Y777500D03*
Y764000D03*
X172000Y757500D03*
X181700Y768400D03*
X165000Y786000D03*
X171500Y819500D03*
X163500Y805500D03*
X177500Y812000D03*
Y826500D03*
X140500Y846500D03*
X134500Y840500D03*
X145500Y885000D03*
X137500Y903000D03*
X146000Y893000D03*
X135000D03*
X134500Y885500D03*
X137500Y876500D03*
X145500Y856500D03*
X157500Y858000D03*
X156300Y877200D03*
X156500Y889000D03*
X153500Y941000D03*
X141000Y938500D03*
X135000Y918000D03*
X135500Y927500D03*
X144000Y919500D03*
Y929000D03*
X143000Y910500D03*
X135500Y909000D03*
X154700Y909700D03*
X154500Y926500D03*
X182000Y950500D03*
X133500Y938000D03*
X134000Y990500D03*
X136500Y967000D03*
X184000Y987500D03*
X135000Y975500D03*
X146800Y1018900D03*
X143900Y1022700D03*
X174000Y1012400D03*
X166300Y1021300D03*
X182500Y1041500D03*
X182000Y1029500D03*
Y1016000D03*
X171000Y1046000D03*
Y1032500D03*
X175000Y1059000D03*
X160500Y1053500D03*
X181000Y1051000D03*
X164700Y1033600D03*
X176000Y1018500D03*
X183500Y1065500D03*
X171000Y1068000D03*
X166000Y1080000D03*
X173000Y1082000D03*
X165000Y1097000D03*
X181000Y1098500D03*
X175000Y1072500D03*
X160500Y1067000D03*
X170000Y1103000D03*
Y1089500D03*
X157000Y1101500D03*
X159500Y1087500D03*
X181000Y1079500D03*
X154600Y1111000D03*
X158500Y1075800D03*
X158595Y1110789D03*
X155000Y1120000D03*
Y1125000D03*
Y1130500D03*
X181000Y1112500D03*
X177102Y1129800D03*
X171502Y1129547D03*
X147500Y1165500D03*
Y1186000D03*
X178644Y1202519D03*
X163344Y1181200D03*
X161500Y1227500D03*
X147500Y1221500D03*
X146500Y1241500D03*
X147000Y1265500D03*
X183500Y1241500D03*
X165000Y1264500D03*
X147500Y1288000D03*
Y1311000D03*
X164500Y1299500D03*
X147500Y1332000D03*
X147000Y1348000D03*
X147500Y1366500D03*
X147000Y1377000D03*
X146500Y1417619D03*
X148300Y1465000D03*
X137000Y1429200D03*
X173375Y1432500D03*
X149686Y1460007D03*
X133500Y1467100D03*
X152500Y1456000D03*
X133799Y1440699D03*
X174000Y1515500D03*
X174500Y1509500D03*
Y1503500D03*
X174000Y1522000D03*
X136000Y1528000D03*
X150000Y1570000D03*
X166898Y1567102D03*
X168500Y1526000D03*
X148000Y1564000D03*
X161300Y1563100D03*
X169500Y1561500D03*
X170000Y1548500D03*
X154000Y1564000D03*
X156000Y1570000D03*
X161400Y1543500D03*
X170000Y1555000D03*
X168500Y1533500D03*
X148000Y1542000D03*
Y1528000D03*
Y1558000D03*
X136000Y1548000D03*
Y1555000D03*
Y1562000D03*
Y1536000D03*
Y1542000D03*
Y1568000D03*
X170000Y1541000D03*
X148000Y1550000D03*
X156000Y1576000D03*
X150000D03*
X156000Y1582000D03*
X156500Y1591000D03*
X150500Y1582000D03*
Y1591000D03*
X172000Y1606000D03*
X182500Y1599400D03*
X146000Y1612000D03*
X148000Y1606000D03*
X182500Y1592000D03*
X164000Y1606000D03*
X156500Y1600000D03*
X156000Y1606000D03*
X150500Y1600000D03*
X138500Y1606000D03*
X182500Y1584500D03*
X141500Y1673000D03*
X176000Y1646000D03*
X166000D03*
X158000D03*
X148000D03*
X176000Y1632000D03*
X178000Y1659500D03*
X167500Y1632500D03*
X170000Y1659500D03*
X149000Y1632500D03*
X159000D03*
X138000Y1634000D03*
X137500Y1659500D03*
X159000D03*
X148500Y1660000D03*
X138000Y1646000D03*
X139000Y1696500D03*
Y1712500D03*
X181500Y1716500D03*
X158500D03*
X167500Y1716000D03*
X182000Y1704000D03*
X168500Y1705000D03*
X158500D03*
X163000Y1697000D03*
X174268Y1697110D03*
X152000D03*
Y1710610D03*
Y1725610D03*
X138500Y1727500D03*
X182000Y1726000D03*
X183600Y1765100D03*
X162500Y1773000D03*
X152500Y1771110D03*
X173268Y1776000D03*
X139000Y1800500D03*
X138000Y1824000D03*
X169000Y1781500D03*
X156500Y1782000D03*
X155500Y1798500D03*
X166500Y1798000D03*
X179000Y1798500D03*
X162000Y1790000D03*
X172768Y1790110D03*
X152000D03*
X139000Y1851000D03*
X138500Y1839500D03*
X161500Y1852500D03*
X183100Y1838300D03*
X160500Y1877500D03*
X173000Y1852610D03*
X151500Y1851110D03*
X161000Y1901500D03*
X194000Y55500D03*
X185000Y45000D03*
X195000D03*
X200000Y55000D03*
Y65000D03*
Y75000D03*
Y85000D03*
X187500Y130500D03*
X190500Y105000D03*
X189500Y120000D03*
X200000Y100000D03*
Y120000D03*
Y140000D03*
X191900Y167700D03*
X191700Y186500D03*
X186000Y143000D03*
X201089Y181700D03*
X197500Y151500D03*
X185500D03*
X191800Y234900D03*
Y221100D03*
X191600Y206900D03*
X201500Y208000D03*
X201000Y222500D03*
X200500Y235000D03*
Y195900D03*
X191900Y244600D03*
X202000Y274000D03*
Y254000D03*
X201089Y282600D03*
X202000Y264000D03*
X187500Y338000D03*
X202000Y340000D03*
Y328000D03*
Y295000D03*
X201089Y305500D03*
Y315500D03*
X184500Y325500D03*
X201500Y378000D03*
X202000Y366500D03*
Y353000D03*
X188500Y364100D03*
X188300Y368600D03*
X192600Y392600D03*
X201089Y388400D03*
X201500Y397500D03*
X200500Y437500D03*
X201000Y430500D03*
X201089Y407000D03*
X200000Y420500D03*
X192471Y397355D03*
X192400Y401900D03*
X186600Y425750D03*
X192300Y410950D03*
X192409Y417655D03*
X186500Y498000D03*
X192000Y490000D03*
Y498000D03*
X200300Y498100D03*
X199500Y489400D03*
X188500Y474500D03*
X189900Y467500D03*
Y460500D03*
X190400Y453500D03*
X195000Y467500D03*
X194500Y474500D03*
X195000Y460500D03*
X195500Y453500D03*
X190239Y447449D03*
X195600Y447500D03*
X186500Y513500D03*
Y506000D03*
X192000Y513500D03*
Y506000D03*
X190200Y523400D03*
X201089Y523500D03*
X186500Y519000D03*
X193600Y519100D03*
X200100Y513600D03*
X199800Y506000D03*
X201200Y519200D03*
X201500Y544500D03*
X201089Y529500D03*
X192400Y529400D03*
X191900Y538200D03*
X201500Y535000D03*
X192000Y543500D03*
X202000Y578000D03*
Y586000D03*
Y595000D03*
X193700D03*
X194400Y586000D03*
X201500Y552500D03*
X201089Y558000D03*
X201500Y564000D03*
X201089Y570600D03*
X190500Y550500D03*
X202000Y607500D03*
X196500Y641500D03*
X192600Y633000D03*
X201500Y621500D03*
X202000Y650500D03*
X194000Y628500D03*
Y615000D03*
X192500Y645000D03*
X195000Y670000D03*
X185000Y673500D03*
X188100Y689100D03*
X197500Y685000D03*
X202000Y676500D03*
X192500Y658500D03*
X191500Y692500D03*
X193100Y679000D03*
X184700Y663900D03*
X196000Y718500D03*
X184500Y708500D03*
X197000Y704000D03*
X195500Y739000D03*
X197500Y753000D03*
X202000Y710000D03*
Y740500D03*
X191500Y724000D03*
Y710500D03*
Y746500D03*
X196000Y789500D03*
X196500Y797000D03*
X187900Y785300D03*
X202000Y765000D03*
Y786000D03*
X191500Y760000D03*
X194500Y782500D03*
Y769000D03*
X196800Y828500D03*
X197000Y815000D03*
X190000Y823500D03*
X190500Y831000D03*
X202000Y807500D03*
X201500Y835500D03*
X192500Y853000D03*
Y839500D03*
X185000Y843500D03*
X184500Y879000D03*
Y865500D03*
X192000Y879000D03*
Y865500D03*
X194000Y907000D03*
Y893500D03*
X187000Y891000D03*
X192000Y934500D03*
Y921000D03*
Y948500D03*
X185000Y917500D03*
X192000Y962000D03*
X192500Y985500D03*
Y972000D03*
X195500Y1001000D03*
X190000Y1052000D03*
X195500Y1014500D03*
X193500Y1042500D03*
Y1029000D03*
X195000Y1086500D03*
X194500Y1100500D03*
X195000Y1074500D03*
Y1061000D03*
X201000Y1106500D03*
Y1093000D03*
X187500Y1103500D03*
Y1090000D03*
X191800Y1280900D03*
X194500Y1546000D03*
X193000Y1556500D03*
X197000Y1551500D03*
X195500Y1530500D03*
X193000Y1562500D03*
X189400Y1544100D03*
X187900Y1566600D03*
X189500Y1577000D03*
X198500Y1584000D03*
X192000Y1586000D03*
X197500Y1593000D03*
X191500Y1595000D03*
X199000Y1619500D03*
X190000Y1622000D03*
X198000Y1632500D03*
X191500Y1631000D03*
X198000Y1647500D03*
X196500Y1656000D03*
X197000Y1713000D03*
Y1691500D03*
X184500Y1696500D03*
X197500Y1776500D03*
Y1754000D03*
X197000Y1735500D03*
X185000Y1738500D03*
X198000Y1818500D03*
X196500Y1800500D03*
X185500Y1804500D03*
X186000Y1790000D03*
X197500Y1860000D03*
X197000Y1838500D03*
X194400Y1876700D03*
X185000Y1852500D03*
X201500Y1900500D03*
X190500Y1924000D03*
X201000Y1923000D03*
X195500Y1905000D03*
X196500Y1882000D03*
X897450Y1813325D03*
G54D21*
X80709Y161889D03*
Y171889D03*
Y181889D03*
Y191889D03*
Y204409D03*
Y214409D03*
Y224409D03*
Y234409D03*
Y244409D03*
Y256929D03*
Y266929D03*
Y276929D03*
Y286929D03*
X110709Y161889D03*
Y171889D03*
X100709Y161889D03*
Y171889D03*
X90709Y161889D03*
Y171889D03*
X110709Y181889D03*
Y191889D03*
X100709Y181889D03*
Y191889D03*
X90709Y181889D03*
Y191889D03*
X110709Y204409D03*
Y214409D03*
Y224409D03*
Y234409D03*
Y244409D03*
X100709Y204409D03*
Y214409D03*
Y224409D03*
Y234409D03*
Y244409D03*
X90709Y204409D03*
Y214409D03*
Y224409D03*
Y234409D03*
Y244409D03*
X110709Y256929D03*
Y266929D03*
X100709Y256929D03*
Y266929D03*
X90709Y256929D03*
Y266929D03*
X110709Y276929D03*
Y286929D03*
X100709Y276929D03*
Y286929D03*
X90709Y276929D03*
Y286929D03*
X179606Y161889D03*
Y171889D03*
X169606Y161889D03*
Y171889D03*
X159606Y161889D03*
Y171889D03*
X149606Y161889D03*
Y171889D03*
X179606Y181889D03*
Y191889D03*
X169606Y181889D03*
Y191889D03*
X159606Y181889D03*
Y191889D03*
X149606Y181889D03*
Y191889D03*
X179606Y204409D03*
Y214409D03*
Y224409D03*
Y234409D03*
Y244409D03*
X169606Y204409D03*
Y214409D03*
Y224409D03*
Y234409D03*
Y244409D03*
X159606Y204409D03*
Y214409D03*
Y224409D03*
Y234409D03*
Y244409D03*
X149606Y204409D03*
Y214409D03*
Y224409D03*
Y234409D03*
Y244409D03*
X179606Y256929D03*
Y266929D03*
X169606Y256929D03*
Y266929D03*
X159606Y256929D03*
Y266929D03*
X149606Y256929D03*
Y266929D03*
X179606Y276929D03*
Y286929D03*
X169606Y276929D03*
Y286929D03*
X159606Y276929D03*
Y286929D03*
X149606Y276929D03*
Y286929D03*
X897450Y1723775D03*
G54D13*
X15906Y48110D03*
Y58110D03*
Y68110D03*
Y78110D03*
Y88110D03*
Y481339D03*
Y491339D03*
Y501339D03*
Y511339D03*
Y521339D03*
Y741181D03*
Y751181D03*
Y761181D03*
Y771181D03*
Y781181D03*
Y1187323D03*
Y1197323D03*
Y1207323D03*
Y1217323D03*
Y1227323D03*
Y1447165D03*
Y1457165D03*
Y1467165D03*
Y1477165D03*
Y1487165D03*
Y1880394D03*
Y1890394D03*
Y1900394D03*
Y1910394D03*
Y1920394D03*
X128937Y1778819D03*
X118937D03*
X165000Y1390500D03*
Y1380500D03*
Y1370500D03*
X138937Y1778819D03*
X897450Y1753625D03*
G54D22*
X96457Y1747835D03*
Y1823031D03*
X178937Y1328740D03*
X161417Y1747835D03*
Y1823031D03*
X897450Y1634225D03*
G54D23*
G01X-448201Y-82763D02*
Y-162763D01*
G01Y-118263D02*
X752899D01*
G01X-448201Y-162763D02*
X752899D01*
G01X-452201Y-66763D02*
G02I-12000J0D01*
G01X-457351D02*
G02I-6850J0D01*
G01X-464201Y-82763D02*
Y-50763D01*
G01X-448201Y-66763D02*
X-480201D01*
G01X-448201Y-82763D02*
X752899D01*
G01X-34601D02*
Y-162763D01*
G01X102899Y-82763D02*
Y-162763D01*
G01X217899Y-82763D02*
Y-162763D01*
G01X385399Y-82763D02*
Y-162763D01*
G01X555399Y-82763D02*
Y-162763D01*
G01X752899Y-82763D02*
Y-162763D01*
G01X780899Y-66763D02*
G02I-12000J0D01*
G01X775749D02*
G02I-6850J0D01*
G01X768899Y-82763D02*
Y-50763D01*
G01X784899Y-66763D02*
X752899D01*
G54D14*
X27559Y157480D03*
X179134Y1889764D03*
X897450Y1664075D03*
G54D24*
G01X-430254Y-152763D02*
Y-135263D01*
G01X-421958D02*
X-430254Y-146055D01*
G01X-420648Y-152763D02*
X-426543Y-141097D01*
G01X-412973Y-152763D02*
Y-135263D01*
X-402929Y-152763D01*
Y-135263D01*
G01X-390451Y-152763D02*
X-392198Y-152471D01*
X-393726Y-151305D01*
X-395036Y-149555D01*
X-395910Y-147513D01*
X-396346Y-145180D01*
Y-142846D01*
X-395910Y-140513D01*
X-395036Y-138471D01*
X-393726Y-136722D01*
X-392198Y-135555D01*
X-390451Y-135263D01*
X-388705Y-135555D01*
X-387176Y-136722D01*
X-385866Y-138471D01*
X-384992Y-140513D01*
X-384556Y-142846D01*
Y-145180D01*
X-384992Y-147513D01*
X-385866Y-149555D01*
X-387176Y-151305D01*
X-388705Y-152471D01*
X-390451Y-152763D01*
G01X-377536D02*
X-368366Y-135263D01*
G01X-377536D02*
X-368366Y-152763D01*
G01X-362001Y-158596D02*
X-348901D01*
G01X-342099Y-152763D02*
Y-135263D01*
X-333803D01*
G01X-336859Y-143721D02*
X-342099D01*
G01X-325910Y-152763D02*
X-320451Y-135263D01*
X-314992Y-152763D01*
G01X-316958Y-146638D02*
X-323945D01*
G01X-307973Y-152763D02*
Y-135263D01*
X-297929Y-152763D01*
Y-135263D01*
G01X-263148Y-136722D02*
X-264458Y-135846D01*
X-265986Y-135263D01*
X-267733D01*
X-269698Y-136138D01*
X-271226Y-137596D01*
X-272318Y-139347D01*
X-273191Y-142263D01*
X-273410Y-144888D01*
X-272973Y-147513D01*
X-272318Y-149263D01*
X-271008Y-151013D01*
X-269479Y-152180D01*
X-267951Y-152763D01*
X-266423D01*
X-264894Y-152180D01*
X-263584Y-151305D01*
X-262492Y-150139D01*
G01X-250451Y-152763D02*
X-252198Y-152471D01*
X-253726Y-151305D01*
X-255036Y-149555D01*
X-255910Y-147513D01*
X-256346Y-145180D01*
Y-142846D01*
X-255910Y-140513D01*
X-255036Y-138471D01*
X-253726Y-136722D01*
X-252198Y-135555D01*
X-250451Y-135263D01*
X-248705Y-135555D01*
X-247176Y-136722D01*
X-245866Y-138471D01*
X-244992Y-140513D01*
X-244556Y-142846D01*
Y-145180D01*
X-244992Y-147513D01*
X-245866Y-149555D01*
X-247176Y-151305D01*
X-248705Y-152471D01*
X-250451Y-152763D01*
G01X-237973D02*
Y-135263D01*
X-227929Y-152763D01*
Y-135263D01*
G01X-215451D02*
Y-152763D01*
G01X-220473Y-135263D02*
X-210429D01*
G01X-202318Y-152763D02*
Y-135263D01*
X-196859D01*
X-195113Y-136138D01*
X-194021Y-137305D01*
X-193584Y-139638D01*
X-194021Y-141972D01*
X-195331Y-143430D01*
X-196859Y-144305D01*
X-202318D01*
G01X-196859D02*
X-193584Y-152763D01*
G01X-180451D02*
X-182198Y-152471D01*
X-183726Y-151305D01*
X-185036Y-149555D01*
X-185910Y-147513D01*
X-186346Y-145180D01*
Y-142846D01*
X-185910Y-140513D01*
X-185036Y-138471D01*
X-183726Y-136722D01*
X-182198Y-135555D01*
X-180451Y-135263D01*
X-178705Y-135555D01*
X-177176Y-136722D01*
X-175866Y-138471D01*
X-174992Y-140513D01*
X-174556Y-142846D01*
Y-145180D01*
X-174992Y-147513D01*
X-175866Y-149555D01*
X-177176Y-151305D01*
X-178705Y-152471D01*
X-180451Y-152763D01*
G01X-167318Y-135263D02*
Y-152763D01*
X-158584D01*
G01X-126205Y-143430D02*
X-125331Y-142555D01*
X-124676Y-141097D01*
X-124239Y-139054D01*
X-124676Y-137305D01*
X-125549Y-136138D01*
X-127078Y-135263D01*
X-132973D01*
Y-152763D01*
X-125768D01*
X-124239Y-151597D01*
X-123366Y-149846D01*
X-122929Y-147805D01*
X-123366Y-145763D01*
X-124676Y-144013D01*
X-126205Y-143430D01*
X-132973D01*
G01X-110451Y-152763D02*
X-112198Y-152471D01*
X-113726Y-151305D01*
X-115036Y-149555D01*
X-115910Y-147513D01*
X-116346Y-145180D01*
Y-142846D01*
X-115910Y-140513D01*
X-115036Y-138471D01*
X-113726Y-136722D01*
X-112198Y-135555D01*
X-110451Y-135263D01*
X-108705Y-135555D01*
X-107176Y-136722D01*
X-105866Y-138471D01*
X-104992Y-140513D01*
X-104556Y-142846D01*
Y-145180D01*
X-104992Y-147513D01*
X-105866Y-149555D01*
X-107176Y-151305D01*
X-108705Y-152471D01*
X-110451Y-152763D01*
G01X-98410D02*
X-92951Y-135263D01*
X-87492Y-152763D01*
G01X-89458Y-146638D02*
X-96445D01*
G01X-79818Y-152763D02*
Y-135263D01*
X-74359D01*
X-72613Y-136138D01*
X-71521Y-137305D01*
X-71084Y-139638D01*
X-71521Y-141972D01*
X-72831Y-143430D01*
X-74359Y-144305D01*
X-79818D01*
G01X-74359D02*
X-71084Y-152763D01*
G01X-62754D02*
Y-135263D01*
X-58388D01*
X-56641Y-136138D01*
X-55331Y-137305D01*
X-54239Y-139054D01*
X-53366Y-141097D01*
X-53148Y-144013D01*
X-53366Y-146930D01*
X-54239Y-148972D01*
X-55331Y-150722D01*
X-56641Y-151888D01*
X-58388Y-152763D01*
X-62754D01*
G01X-282378Y-107763D02*
Y-90263D01*
X-276701Y-104846D01*
X-271024Y-90263D01*
Y-107763D01*
G01X-259201D02*
X-260511Y-107471D01*
X-261821Y-106305D01*
X-262695Y-104263D01*
X-263131Y-101930D01*
X-262695Y-99596D01*
X-261821Y-97555D01*
X-260511Y-96388D01*
X-259201Y-96097D01*
X-257891Y-96388D01*
X-256581Y-97555D01*
X-255708Y-99596D01*
X-255489Y-101930D01*
X-255708Y-104263D01*
X-256581Y-106305D01*
X-257891Y-107471D01*
X-259201Y-107763D01*
G01X-237771Y-90263D02*
Y-107763D01*
G01Y-105139D02*
X-238644Y-106597D01*
X-239955Y-107471D01*
X-241483Y-107763D01*
X-243229Y-107180D01*
X-244539Y-105722D01*
X-245413Y-103972D01*
X-245631Y-101930D01*
X-245413Y-99888D01*
X-244539Y-98138D01*
X-243229Y-96680D01*
X-241483Y-96097D01*
X-239955Y-96388D01*
X-238863Y-96972D01*
X-237771Y-98138D01*
G01X-227476Y-99888D02*
X-220489D01*
X-221144Y-97846D01*
X-222236Y-96680D01*
X-223764Y-96097D01*
X-225293Y-96388D01*
X-226603Y-97263D01*
X-227476Y-99305D01*
X-227913Y-101055D01*
Y-102805D01*
X-227476Y-104555D01*
X-226384Y-106305D01*
X-225074Y-107471D01*
X-223546Y-107763D01*
X-222018Y-107180D01*
X-220489Y-105430D01*
G01X-206701Y-107763D02*
Y-90263D01*
G01X-242126Y15000D02*
G03X-227126Y0I15000J0D01*
G01X-242126Y1953504D02*
Y15000D01*
G01X-215453Y19685D02*
G03I-6988J0D01*
G01X-84646Y0D02*
X-227126D01*
G01X-215453Y19685D02*
G03I-6988J0D01*
G01D02*
G03I-6988J0D01*
G01X-227126Y1968504D02*
G03X-242126Y1953504I0J-15000D01*
G01X-215453Y1948819D02*
G03I-6988J0D01*
G01X-84638Y1968504D02*
X-227126D01*
G01X-215453Y1948819D02*
G03I-6988J0D01*
G01D02*
G03I-6988J0D01*
G01X-222441Y39370D02*
G03X-214567Y31496I7874J0D01*
G01X-206693D02*
X-214567D01*
G01X-175984D02*
X-84646D01*
G01X-206693D02*
G03Y39370I0J3937D01*
G01X-175984D02*
G03Y31496I0J-3937D01*
G01X-206693D02*
X-214567D01*
G01X-84646Y0D02*
X-199567D01*
G01X-175984Y31496D02*
X-84646D01*
G01X-206693D02*
G03Y39370I0J3937D01*
G01X-175984D02*
G03Y31496I0J-3937D01*
G01X-222441Y169326D02*
Y39370D01*
G01X-214567Y43307D02*
G03X-210630Y39370I3937J0D01*
G01X-214567Y43307D02*
G03X-210630Y39370I3937J0D01*
G01X-80709D02*
X-210630D01*
G01X-80709D02*
X-210630D01*
G01X-214567Y43307D02*
Y1925197D01*
G01Y43307D02*
Y1925197D01*
G01Y149606D02*
Y43307D01*
G01Y149606D02*
Y43272D01*
G01Y169326D02*
G03X-222441I-3937J0D01*
G01X-214567D02*
G03X-222441I-3937J0D01*
G01X-214567Y1807087D02*
Y161417D01*
G01Y1807087D02*
Y161417D01*
G01X-222441Y436255D02*
Y200034D01*
G01D02*
G03X-214567I3937J0D01*
G01X-222441D02*
G03X-214567I3937J0D01*
G01Y436255D02*
G03X-222441I-3937J0D01*
G01X-214567D02*
G03X-222441I-3937J0D01*
G01Y703184D02*
Y466963D01*
G01D02*
G03X-214567I3937J0D01*
G01X-222441D02*
G03X-214567I3937J0D01*
G01X-222441Y970901D02*
Y733892D01*
G01X-214567Y703184D02*
G03X-222441I-3937J0D01*
G01Y733892D02*
G03X-214567I3937J0D01*
G01Y703184D02*
G03X-222441I-3937J0D01*
G01Y733892D02*
G03X-214567I3937J0D01*
G01X-222441Y1234681D02*
Y997672D01*
G01X-214567Y970901D02*
G03X-222441I-3937J0D01*
G01Y997672D02*
G03X-214567I3937J0D01*
G01Y970901D02*
G03X-222441I-3937J0D01*
G01Y997672D02*
G03X-214567I3937J0D01*
G01X-222441Y1265389D02*
G03X-214567I3937J0D01*
G01Y1234681D02*
G03X-222441I-3937J0D01*
G01Y1265389D02*
G03X-214567I3937J0D01*
G01Y1234681D02*
G03X-222441I-3937J0D01*
G01Y1501610D02*
Y1265389D01*
G01X-214567Y1501610D02*
G03X-222441I-3937J0D01*
G01X-214567D02*
G03X-222441I-3937J0D01*
G01Y1768539D02*
Y1532318D01*
G01D02*
G03X-214567I3937J0D01*
G01X-222441D02*
G03X-214567I3937J0D01*
G01Y1768539D02*
G03X-222441I-3937J0D01*
G01X-214567D02*
G03X-222441I-3937J0D01*
G01Y1799247D02*
G03X-214567I3937J0D01*
G01X-222441D02*
G03X-214567I3937J0D01*
G01X-222441Y1929134D02*
Y1799247D01*
G01X-214567Y1818898D02*
Y1925231D01*
G01Y1818898D02*
Y1925231D01*
G01X-210630Y1929134D02*
G03X-214567Y1925197I0J-3937D01*
G01X-210630Y1929134D02*
G03X-214567Y1925197I0J-3937D01*
G01Y1937008D02*
G03X-222441Y1929134I0J-7874D01*
G01X-210630D02*
X-80709D01*
G01X-210630D02*
X-80709D01*
G01X-175984Y1937008D02*
X-84638D01*
G01X-214567D02*
X-206693D01*
G01X-175984D02*
G03Y1929134I0J-3937D01*
G01X-206693D02*
G03Y1937008I0J3937D01*
G01X-84638Y1968504D02*
X-199567D01*
G01X-175984Y1937008D02*
X-84638D01*
G01X-214567D02*
X-206693D01*
G01X-175984D02*
G03Y1929134I0J-3937D01*
G01X-206693D02*
G03Y1937008I0J3937D01*
G01X-76772Y3937D02*
G03X-72835Y0I3937J0D01*
G01X-76772Y35433D02*
G03X-80709Y39370I-3937J0D01*
G01X-76772Y35433D02*
G03X-80709Y39370I-3937J0D01*
G01X-76772Y3937D02*
G03X-72835Y0I3937J0D01*
G01X-76772Y3937D02*
Y35433D01*
G01Y3937D02*
Y35433D01*
G01Y3937D02*
G03X-72835Y0I3937J0D01*
G01X-84646Y7874D02*
Y0D01*
G01X-76772Y7874D02*
G03X-84646I-3937J0D01*
G01Y31496D02*
G03X-76772I3937J0D01*
G01Y3937D02*
G03X-72835Y0I3937J0D01*
G01X-84646Y7874D02*
Y0D01*
G01X-76772Y7874D02*
G03X-84646I-3937J0D01*
G01Y31496D02*
G03X-76772I3937J0D01*
G01X-76763Y1937008D02*
G03X-84638I-3937J0D01*
G01X-80709Y1929134D02*
G03X-76772Y1933071I0J3937D01*
G01X-80709Y1929134D02*
G03X-76772Y1933071I0J3937D01*
G01X-72835Y1968504D02*
G03X-76772Y1964567I0J-3937D01*
G01X-72835Y1968504D02*
G03X-76772Y1964567I0J-3937D01*
G01Y1933071D02*
Y1964567D01*
G01Y1933071D02*
Y1964567D01*
G01X-72835Y1968504D02*
G03X-76772Y1964567I0J-3937D01*
G01X-84638Y1960889D02*
Y1968504D01*
G01Y1960889D02*
G03X-76763I3938J0D01*
G01X-72835Y1968504D02*
G03X-76772Y1964567I0J-3937D01*
G01X-84638Y1960889D02*
Y1968504D01*
G01Y1960889D02*
G03X-76763I3938J0D01*
G01X-11811Y0D02*
X-72835D01*
G01X-11811D02*
X-72835D01*
G01D02*
X-11811D01*
G01X-72835D02*
X-11811D01*
G01X-72835Y1968504D02*
X-11811D01*
G01X-72835D02*
X-11811D01*
G01D02*
X-72835D01*
G01X-11811D02*
X-72835D01*
G01X-901Y-152763D02*
Y-135263D01*
X-3521Y-138763D01*
G01Y-152763D02*
X1719D01*
G01X12451Y-138180D02*
X13761Y-136430D01*
X15289Y-135555D01*
X17036Y-135263D01*
X19219Y-135846D01*
X20747Y-137305D01*
X21184Y-139054D01*
X20966Y-140805D01*
X20092Y-142263D01*
X15726Y-145180D01*
X13761Y-147221D01*
X12451Y-150139D01*
X12014Y-152763D01*
X21184D01*
G01X36719D02*
Y-135263D01*
X28640Y-147805D01*
X39558D01*
G01X46796Y-149263D02*
X48105Y-151305D01*
X49852Y-152471D01*
X51817Y-152763D01*
X53564Y-152471D01*
X55311Y-151013D01*
X56402Y-149263D01*
X56621Y-147513D01*
X56184Y-145472D01*
X54656Y-144013D01*
X53127Y-143430D01*
X51162D01*
G01X53127D02*
X54437Y-142555D01*
X55529Y-141097D01*
X55966Y-139347D01*
X55529Y-137596D01*
X54437Y-136138D01*
X52472Y-135263D01*
X50507Y-135555D01*
X48542Y-136722D01*
G01X64296Y-149263D02*
X65605Y-151305D01*
X67352Y-152471D01*
X69317Y-152763D01*
X71064Y-152471D01*
X72811Y-151013D01*
X73902Y-149263D01*
X74121Y-147513D01*
X73684Y-145472D01*
X72156Y-144013D01*
X70627Y-143430D01*
X68662D01*
G01X70627D02*
X71937Y-142555D01*
X73029Y-141097D01*
X73466Y-139347D01*
X73029Y-137596D01*
X71937Y-136138D01*
X69972Y-135263D01*
X68007Y-135555D01*
X66042Y-136722D01*
G01X-14018Y-107763D02*
Y-90263D01*
X-8778D01*
X-7031Y-91138D01*
X-5721Y-93180D01*
X-5284Y-95513D01*
X-5721Y-97846D01*
X-6813Y-99596D01*
X-8778Y-100472D01*
X-14018D01*
G01X12652Y-91722D02*
X11342Y-90846D01*
X9814Y-90263D01*
X8067D01*
X6102Y-91138D01*
X4574Y-92596D01*
X3482Y-94347D01*
X2609Y-97263D01*
X2390Y-99888D01*
X2827Y-102513D01*
X3482Y-104263D01*
X4792Y-106013D01*
X6321Y-107180D01*
X7849Y-107763D01*
X9377D01*
X10906Y-107180D01*
X12216Y-106305D01*
X13308Y-105139D01*
G01X27095Y-98430D02*
X27969Y-97555D01*
X28624Y-96097D01*
X29061Y-94054D01*
X28624Y-92305D01*
X27751Y-91138D01*
X26222Y-90263D01*
X20327D01*
Y-107763D01*
X27532D01*
X29061Y-106597D01*
X29934Y-104846D01*
X30371Y-102805D01*
X29934Y-100763D01*
X28624Y-99013D01*
X27095Y-98430D01*
X20327D01*
G01X36299Y-113596D02*
X49399D01*
G01X55327Y-107763D02*
Y-90263D01*
X65371Y-107763D01*
Y-90263D01*
G01X77849Y-107763D02*
X76102Y-107471D01*
X74574Y-106305D01*
X73264Y-104555D01*
X72390Y-102513D01*
X71954Y-100180D01*
Y-97846D01*
X72390Y-95513D01*
X73264Y-93471D01*
X74574Y-91722D01*
X76102Y-90555D01*
X77849Y-90263D01*
X79595Y-90555D01*
X81124Y-91722D01*
X82434Y-93471D01*
X83308Y-95513D01*
X83744Y-97846D01*
Y-100180D01*
X83308Y-102513D01*
X82434Y-104555D01*
X81124Y-106305D01*
X79595Y-107471D01*
X77849Y-107763D01*
G01X-11811Y0D02*
G03X-7874Y3937I0J3937D01*
G01X-11811Y0D02*
G03X-7874Y3937I0J3937D01*
G01Y43110D02*
Y3937D01*
G01Y43110D02*
Y3937D01*
G01X0D02*
G03X3937Y0I3937J0D01*
G01X0Y3937D02*
G03X3937Y0I3937J0D01*
G01X0Y3937D02*
Y43110D01*
G01Y3937D02*
Y43110D01*
G01X64961Y0D02*
X3937D01*
G01X64961D02*
X3937D01*
G01X0Y3937D02*
G03X3937Y0I3937J0D01*
G01X0Y1964567D02*
Y3937D01*
G01X3937Y0D02*
X64961D01*
G01X-7874Y3937D02*
Y1964567D01*
G01X-11811Y0D02*
G03X-7874Y3937I0J3937D01*
G01X0Y11811D02*
G03X-7874I-3937J0D01*
G01X0Y3937D02*
G03X3937Y0I3937J0D01*
G01X0Y1964567D02*
Y3937D01*
G01X3937Y0D02*
X64961D01*
G01X-7874Y3937D02*
Y1964567D01*
G01X-11811Y0D02*
G03X-7874Y3937I0J3937D01*
G01X0Y11811D02*
G03X-7874I-3937J0D01*
G01Y93110D02*
Y43110D01*
G01Y93110D02*
Y43110D01*
G01X0D02*
Y93110D01*
G01Y43110D02*
Y93110D01*
G01X-7874Y42520D02*
G03X0I3937J0D01*
G01X-7874D02*
G03X0I3937J0D01*
G01X-7874Y214764D02*
Y93110D01*
G01Y214764D02*
Y93110D01*
G01X0D02*
Y214764D01*
G01Y93110D02*
Y214764D01*
G01X-7874Y226968D02*
Y214764D01*
G01Y226968D02*
Y214764D01*
G01Y342461D02*
Y226968D01*
G01Y342461D02*
Y226968D01*
G01X0Y226969D02*
Y342461D01*
G01Y226969D02*
Y342461D01*
G01Y214764D02*
Y226969D01*
G01Y214764D02*
Y226969D01*
G01Y278740D02*
G03X-7874I-3937J0D01*
G01X0D02*
G03X-7874I-3937J0D01*
G01Y354665D02*
Y342461D01*
G01Y354665D02*
Y342461D01*
G01X0D02*
Y354665D01*
G01Y342461D02*
Y354665D01*
G01X-7874Y309449D02*
G03X0I3937J0D01*
G01X-7874D02*
G03X0I3937J0D01*
G01X-7874Y476339D02*
Y354665D01*
G01Y476339D02*
Y354665D01*
G01X0D02*
Y476339D01*
G01Y354665D02*
Y476339D01*
G01X-7874Y526339D02*
Y476339D01*
G01Y526339D02*
Y476339D01*
G01X0D02*
Y526339D01*
G01Y476339D02*
Y526339D01*
G01X-7874Y736181D02*
Y526339D01*
G01Y736181D02*
Y526339D01*
G01X0D02*
Y736181D01*
G01Y526339D02*
Y736181D01*
G01Y545669D02*
G03X-7874I-3937J0D01*
G01X0D02*
G03X-7874I-3937J0D01*
G01Y576378D02*
G03X0I3937J0D01*
G01X-7874D02*
G03X0I3937J0D01*
G01X-7874Y786181D02*
Y736181D01*
G01Y786181D02*
Y736181D01*
G01X0D02*
Y786181D01*
G01Y736181D02*
Y786181D01*
G01X-7874Y907815D02*
Y786181D01*
G01Y907815D02*
Y786181D01*
G01X0D02*
Y907815D01*
G01Y786181D02*
Y907815D01*
G01Y831496D02*
G03X-7874I-3937J0D01*
G01X0D02*
G03X-7874I-3937J0D01*
G01Y862205D02*
G03X0I3937J0D01*
G01X-7874D02*
G03X0I3937J0D01*
G01X-7874Y920020D02*
Y907815D01*
G01Y920020D02*
Y907815D01*
G01Y1048484D02*
Y920020D01*
G01Y1048484D02*
Y920020D01*
G01X0D02*
Y1048484D01*
G01Y920020D02*
Y1048484D01*
G01Y907815D02*
Y920020D01*
G01Y907815D02*
Y920020D01*
G01X-7874Y1060689D02*
Y1048484D01*
G01Y1060689D02*
Y1048484D01*
G01X0D02*
Y1060689D01*
G01Y1048484D02*
Y1060689D01*
G01X-7874Y1182323D02*
Y1060689D01*
G01Y1182323D02*
Y1060689D01*
G01X0D02*
Y1182323D01*
G01Y1060689D02*
Y1182323D01*
G01Y1106299D02*
G03X-7874I-3937J0D01*
G01X0D02*
G03X-7874I-3937J0D01*
G01Y1137008D02*
G03X0I3937J0D01*
G01X-7874D02*
G03X0I3937J0D01*
G01X-7874Y1232323D02*
Y1182323D01*
G01Y1232323D02*
Y1182323D01*
G01X0D02*
Y1232323D01*
G01Y1182323D02*
Y1232323D01*
G01X-7874Y1442165D02*
Y1232323D01*
G01Y1442165D02*
Y1232323D01*
G01X0D02*
Y1442165D01*
G01Y1232323D02*
Y1442165D01*
G01Y1392126D02*
G03X-7874I-3937J0D01*
G01X0D02*
G03X-7874I-3937J0D01*
G01Y1492165D02*
Y1442165D01*
G01Y1492165D02*
Y1442165D01*
G01X0D02*
Y1492165D01*
G01Y1442165D02*
Y1492165D01*
G01X-7874Y1422835D02*
G03X0I3937J0D01*
G01X-7874D02*
G03X0I3937J0D01*
G01X-7874Y1613839D02*
Y1492165D01*
G01Y1613839D02*
Y1492165D01*
G01X0D02*
Y1613839D01*
G01Y1492165D02*
Y1613839D01*
G01X-7874Y1626043D02*
Y1613839D01*
G01Y1626043D02*
Y1613839D01*
G01X0D02*
Y1626043D01*
G01Y1613839D02*
Y1626043D01*
G01X-7874Y1741535D02*
Y1626043D01*
G01Y1741535D02*
Y1626043D01*
G01X0D02*
Y1741535D01*
G01Y1626043D02*
Y1741535D01*
G01Y1659055D02*
G03X-7874I-3937J0D01*
G01X0D02*
G03X-7874I-3937J0D01*
G01Y1689764D02*
G03X0I3937J0D01*
G01X-7874D02*
G03X0I3937J0D01*
G01X-7874Y1753740D02*
Y1741535D01*
G01Y1753740D02*
Y1741535D01*
G01Y1875394D02*
Y1753740D01*
G01Y1875394D02*
Y1753740D01*
G01X0D02*
Y1875394D01*
G01Y1753740D02*
Y1875394D01*
G01Y1741535D02*
Y1753740D01*
G01Y1741535D02*
Y1753740D01*
G01X-7874Y1925394D02*
Y1875394D01*
G01Y1925394D02*
Y1875394D01*
G01X0D02*
Y1925394D01*
G01Y1875394D02*
Y1925394D01*
G01X-7874Y1964567D02*
Y1925394D01*
G01Y1964567D02*
Y1925394D01*
G01X0D02*
Y1964567D01*
G01Y1925394D02*
Y1964567D01*
G01Y1925984D02*
G03X-7874I-3937J0D01*
G01X0D02*
G03X-7874I-3937J0D01*
G01Y1964567D02*
G03X-11811Y1968504I-3937J0D01*
G01X-7874Y1964567D02*
G03X-11811Y1968504I-3937J0D01*
G01X3937D02*
G03X0Y1964567I0J-3937D01*
G01X3937Y1968504D02*
G03X0Y1964567I0J-3937D01*
G01X3937Y1968504D02*
X64961D01*
G01X3937D02*
X64961D01*
G01X3937D02*
G03X0Y1964567I0J-3937D01*
G01X64961Y1968504D02*
X3937D01*
G01X-7874Y1964567D02*
G03X-11811Y1968504I-3937J0D01*
G01X-7874Y1956693D02*
G03X0I3937J0D01*
G01X3937Y1968504D02*
G03X0Y1964567I0J-3937D01*
G01X64961Y1968504D02*
X3937D01*
G01X-7874Y1964567D02*
G03X-11811Y1968504I-3937J0D01*
G01X-7874Y1956693D02*
G03X0I3937J0D01*
G01X168110Y31496D02*
X76763D01*
G01X72835Y39370D02*
G03X68898Y35433I0J-3937D01*
G01X72835Y39370D02*
G03X68898Y35433I0J-3937D01*
G01X64961Y0D02*
G03X68898Y3937I0J3937D01*
G01X64961Y0D02*
G03X68898Y3937I0J3937D01*
G01Y35433D02*
Y3937D01*
G01Y35433D02*
Y3937D01*
G01X72835Y39370D02*
G03X68898Y35433I0J-3937D01*
G01Y3937D02*
Y35485D01*
G01X64961Y0D02*
G03X68898Y3937I0J3937D01*
G01X76763D02*
G03X80700Y0I3937J0D01*
G01X76763Y7615D02*
Y3937D01*
G01X168110Y31496D02*
X76763D01*
G01Y7615D02*
G03X68889I-3937J0D01*
G01Y31496D02*
G03X76763I3937J0D01*
G01X72835Y39370D02*
G03X68898Y35433I0J-3937D01*
G01Y3937D02*
Y35485D01*
G01X64961Y0D02*
G03X68898Y3937I0J3937D01*
G01X76763D02*
G03X80700Y0I3937J0D01*
G01X76763Y7615D02*
Y3937D01*
G01X168110Y31496D02*
X76763D01*
G01Y7615D02*
G03X68889I-3937J0D01*
G01Y31496D02*
G03X76763I3937J0D01*
G01X202756Y39370D02*
X72835D01*
G01X202756D02*
X72835D01*
G01D02*
X202756D01*
G01X72835D02*
X202756D01*
G01X68898Y1964567D02*
G03X64961Y1968504I-3937J0D01*
G01X68898Y1933071D02*
G03X72835Y1929134I3937J0D01*
G01X68898Y1933071D02*
G03X72835Y1929134I3937J0D01*
G01X68898Y1964567D02*
G03X64961Y1968504I-3937J0D01*
G01X72835Y1929134D02*
X202756D01*
G01X72835D02*
X202756D01*
G01X68898Y1964567D02*
Y1933071D01*
G01Y1964567D02*
Y1933071D01*
G01Y1964567D02*
G03X64961Y1968504I-3937J0D01*
G01X68898Y1933071D02*
Y1964567D01*
G01Y1933071D02*
G03X72835Y1929134I3937J0D01*
G01X202756D02*
X72835D01*
G01X80709Y1968504D02*
G03X76772Y1964567I0J-3937D01*
G01Y1960630D02*
Y1964567D01*
G01X168110Y1937008D02*
X76772D01*
G01X68898Y1960630D02*
G03X76772I3937J0D01*
G01Y1937008D02*
G03X68898I-3937J0D01*
G01Y1964567D02*
G03X64961Y1968504I-3937J0D01*
G01X68898Y1933071D02*
Y1964567D01*
G01Y1933071D02*
G03X72835Y1929134I3937J0D01*
G01X202756D02*
X72835D01*
G01X80709Y1968504D02*
G03X76772Y1964567I0J-3937D01*
G01Y1960630D02*
Y1964567D01*
G01X168110Y1937008D02*
X76772D01*
G01X68898Y1960630D02*
G03X76772I3937J0D01*
G01Y1937008D02*
G03X68898I-3937J0D01*
G01X128690Y-90263D02*
X134149Y-107763D01*
X139608Y-90263D01*
G01X156016Y-107763D02*
X147282D01*
Y-90263D01*
X156016D01*
G01X152522Y-98721D02*
X147282D01*
G01X164782Y-107763D02*
Y-90263D01*
X170241D01*
X171987Y-91138D01*
X173079Y-92305D01*
X173516Y-94638D01*
X173079Y-96972D01*
X171769Y-98430D01*
X170241Y-99305D01*
X164782D01*
G01X170241D02*
X173516Y-107763D01*
G01X186649Y-108346D02*
X186212Y-108055D01*
Y-107471D01*
X186649Y-107180D01*
X187086Y-107471D01*
Y-108055D01*
X186649Y-108346D01*
G01X80700Y0D02*
X340551D01*
G01X80700D02*
X340551D01*
G01X118011Y1968504D02*
X142520D01*
G01X109377D02*
X110137D01*
G01X109377D02*
X80709D01*
G01X110137D02*
G03X118011I3937J0D01*
G01X109377D02*
X80709D01*
G01X110137D02*
G03X118011I3937J0D01*
G01X151649Y-152763D02*
Y-135263D01*
X149029Y-138763D01*
G01Y-152763D02*
X154269D01*
G01X163472D02*
Y-135263D01*
X169149Y-149846D01*
X174826Y-135263D01*
Y-152763D01*
G01X168110Y31496D02*
G03Y39370I0J3937D01*
G01Y31496D02*
G03Y39370I0J3937D01*
G01X340559Y1968504D02*
X142520D01*
G01X168110Y1929134D02*
G03Y1937008I0J3937D01*
G01X340559Y1968504D02*
X142520D01*
G01X168110Y1929134D02*
G03Y1937008I0J3937D01*
G01X222441Y31496D02*
X198819D01*
G01X222441D02*
G03Y39370I0J3937D01*
G01X198819D02*
G03Y31496I0J-3937D01*
G01X222441D02*
X198819D01*
G01X222441D02*
G03Y39370I0J3937D01*
G01X198819D02*
G03Y31496I0J-3937D01*
G01X214567Y161417D02*
Y43307D01*
G01X202756Y39370D02*
G03X206693Y43307I0J3937D01*
G01X202756Y39370D02*
G03X206693Y43307I0J3937D01*
G01Y1925197D02*
Y43307D01*
G01Y1925197D02*
Y43307D01*
G01X202756Y39370D02*
G03X206693Y43307I0J3937D01*
G01X218504Y39370D02*
X348425D01*
G01X214567Y43307D02*
G03X218504Y39370I3937J0D01*
G01X202756D02*
G03X206693Y43307I0J3937D01*
G01X218504Y39370D02*
X348425D01*
G01X214567Y43307D02*
G03X218504Y39370I3937J0D01*
G01X206693Y161417D02*
Y1807087D01*
G01X214567D02*
Y161417D01*
G01Y169291D02*
G03X206693I-3937J0D01*
G01Y161417D02*
Y1807087D01*
G01X214567D02*
Y161417D01*
G01Y169291D02*
G03X206693I-3937J0D01*
G01Y200000D02*
G03X214567I3937J0D01*
G01X206693D02*
G03X214567I3937J0D01*
G01Y436220D02*
G03X206693I-3937J0D01*
G01X214567D02*
G03X206693I-3937J0D01*
G01Y466929D02*
G03X214567I3937J0D01*
G01X206693D02*
G03X214567I3937J0D01*
G01Y703149D02*
G03X206693I-3937J0D01*
G01Y733858D02*
G03X214567I3937J0D01*
G01Y703149D02*
G03X206693I-3937J0D01*
G01Y733858D02*
G03X214567I3937J0D01*
G01Y970867D02*
G03X206693I-3937J0D01*
G01Y997637D02*
G03X214567I3937J0D01*
G01Y970867D02*
G03X206693I-3937J0D01*
G01Y997637D02*
G03X214567I3937J0D01*
G01X206693Y1265355D02*
G03X214567I3937J0D01*
G01Y1234646D02*
G03X206693I-3937J0D01*
G01Y1265355D02*
G03X214567I3937J0D01*
G01Y1234646D02*
G03X206693I-3937J0D01*
G01X214567Y1501575D02*
G03X206693I-3937J0D01*
G01X214567D02*
G03X206693I-3937J0D01*
G01Y1532284D02*
G03X214567I3937J0D01*
G01X206693D02*
G03X214567I3937J0D01*
G01Y1768504D02*
G03X206693I-3937J0D01*
G01X214567D02*
G03X206693I-3937J0D01*
G01X214567Y1807087D02*
Y1925197D01*
G01X206693Y1799213D02*
G03X214567I3937J0D01*
G01X206693D02*
G03X214567I3937J0D01*
G01X206693Y1925197D02*
G03X202756Y1929134I-3937J0D01*
G01X206693Y1925197D02*
G03X202756Y1929134I-3937J0D01*
G01X206693Y1925197D02*
G03X202756Y1929134I-3937J0D01*
G01X218504D02*
G03X214567Y1925197I0J-3937D01*
G01X206693D02*
G03X202756Y1929134I-3937J0D01*
G01X218504D02*
G03X214567Y1925197I0J-3937D01*
G01X348425Y1929134D02*
X218504D01*
G01X198819Y1937008D02*
X222441D01*
G01X198819D02*
G03Y1929134I0J-3937D01*
G01X222441D02*
G03Y1937008I0J3937D01*
G01X348425Y1929134D02*
X218504D01*
G01X198819Y1937008D02*
X222441D01*
G01X198819D02*
G03Y1929134I0J-3937D01*
G01X222441D02*
G03Y1937008I0J3937D01*
G01X261796Y-152763D02*
Y-135263D01*
X266162D01*
X267909Y-136138D01*
X269219Y-137305D01*
X270311Y-139054D01*
X271184Y-141097D01*
X271402Y-144013D01*
X271184Y-146930D01*
X270311Y-148972D01*
X269219Y-150722D01*
X267909Y-151888D01*
X266162Y-152763D01*
X261796D01*
G01X279732D02*
Y-135263D01*
X285191D01*
X286937Y-136138D01*
X288029Y-137305D01*
X288466Y-139638D01*
X288029Y-141972D01*
X286719Y-143430D01*
X285191Y-144305D01*
X279732D01*
G01X285191D02*
X288466Y-152763D01*
G01X298979Y-135263D02*
X304219D01*
G01X301599D02*
Y-152763D01*
G01X298979D02*
X304219D01*
G01X314732Y-135263D02*
Y-152763D01*
X323466D01*
G01X332232Y-135263D02*
Y-152763D01*
X340966D01*
G01X253482Y-90263D02*
Y-107763D01*
X262216D01*
G01X279279D02*
Y-96097D01*
G01Y-98138D02*
X278406Y-96972D01*
X277095Y-96388D01*
X275567Y-96097D01*
X274039Y-96680D01*
X272729Y-97846D01*
X271855Y-99596D01*
X271419Y-101930D01*
X271855Y-104263D01*
X272729Y-106013D01*
X274039Y-107180D01*
X275567Y-107763D01*
X277095Y-107471D01*
X278406Y-106597D01*
X279279Y-105430D01*
G01X288264Y-113013D02*
X289574Y-113596D01*
X291321Y-113013D01*
X292412Y-111847D01*
X293286Y-110388D01*
X294595Y-105722D01*
X297434Y-96097D01*
G01X290447D02*
X294595Y-105722D01*
G01X307074Y-99888D02*
X314061D01*
X313406Y-97846D01*
X312314Y-96680D01*
X310786Y-96097D01*
X309257Y-96388D01*
X307947Y-97263D01*
X307074Y-99305D01*
X306637Y-101055D01*
Y-102805D01*
X307074Y-104555D01*
X308166Y-106305D01*
X309476Y-107471D01*
X311004Y-107763D01*
X312532Y-107180D01*
X314061Y-105430D01*
G01X324792Y-107763D02*
Y-96097D01*
G01Y-98430D02*
X325884Y-97263D01*
X326976Y-96388D01*
X328504Y-96097D01*
X329595Y-96388D01*
X330906Y-97263D01*
G01X342074Y-105722D02*
X343166Y-106888D01*
X344694Y-107763D01*
X346004D01*
X347314Y-107180D01*
X348187Y-106305D01*
X348624Y-105139D01*
X348406Y-103388D01*
X347532Y-102513D01*
X343602Y-100763D01*
X342729Y-98721D01*
X343166Y-97263D01*
X344039Y-96388D01*
X345349Y-96097D01*
X346659Y-96388D01*
X347969Y-97263D01*
G01X253150Y31496D02*
X344488D01*
G01X253150Y39370D02*
G03Y31496I0J-3937D01*
G01D02*
X344488D01*
G01X253150Y39370D02*
G03Y31496I0J-3937D01*
G01Y1937008D02*
X344496D01*
G01X253150D02*
G03Y1929134I0J-3937D01*
G01Y1937008D02*
X344496D01*
G01X253150D02*
G03Y1929134I0J-3937D01*
G01X356299Y0D02*
X417323D01*
G01X352362Y3937D02*
G03X356299Y0I3937J0D01*
G01X352362Y35433D02*
Y3937D01*
G01Y35433D02*
G03X348425Y39370I-3937J0D01*
G01X340551Y0D02*
G03X344488Y3937I0J3937D01*
G01Y7874D02*
Y3937D01*
G01X352362Y7874D02*
G03X344488I-3937J0D01*
G01Y31496D02*
G03X352362I3937J0D01*
G01X356299Y0D02*
X417323D01*
G01X352362Y3937D02*
G03X356299Y0I3937J0D01*
G01X352362Y35433D02*
Y3937D01*
G01Y35433D02*
G03X348425Y39370I-3937J0D01*
G01X340551Y0D02*
G03X344488Y3937I0J3937D01*
G01Y7874D02*
Y3937D01*
G01X352362Y7874D02*
G03X344488I-3937J0D01*
G01Y31496D02*
G03X352362I3937J0D01*
G01X348425Y1929134D02*
G03X352362Y1933071I0J3937D01*
G01Y1964567D02*
Y1933071D01*
G01X356299Y1968504D02*
G03X352362Y1964567I0J-3937D01*
G01X417323Y1968504D02*
X356299D01*
G01X344496Y1964567D02*
G03X340559Y1968504I-3937J0D01*
G01X344496Y1960889D02*
Y1964567D01*
G01Y1960889D02*
G03X352370I3937J0D01*
G01Y1937008D02*
G03X344496I-3937J0D01*
G01X348425Y1929134D02*
G03X352362Y1933071I0J3937D01*
G01Y1964567D02*
Y1933071D01*
G01X356299Y1968504D02*
G03X352362Y1964567I0J-3937D01*
G01X417323Y1968504D02*
X356299D01*
G01X344496Y1964567D02*
G03X340559Y1968504I-3937J0D01*
G01X344496Y1960889D02*
Y1964567D01*
G01Y1960889D02*
G03X352370I3937J0D01*
G01Y1937008D02*
G03X344496I-3937J0D01*
G01X404346Y-107763D02*
Y-90263D01*
X408712D01*
X410459Y-91138D01*
X411769Y-92305D01*
X412861Y-94054D01*
X413734Y-96097D01*
X413952Y-99013D01*
X413734Y-101930D01*
X412861Y-103972D01*
X411769Y-105722D01*
X410459Y-106888D01*
X408712Y-107763D01*
X404346D01*
G01X423374Y-99888D02*
X430361D01*
X429706Y-97846D01*
X428614Y-96680D01*
X427086Y-96097D01*
X425557Y-96388D01*
X424247Y-97263D01*
X423374Y-99305D01*
X422937Y-101055D01*
Y-102805D01*
X423374Y-104555D01*
X424466Y-106305D01*
X425776Y-107471D01*
X427304Y-107763D01*
X428832Y-107180D01*
X430361Y-105430D01*
G01X440874Y-105722D02*
X441966Y-106888D01*
X443494Y-107763D01*
X444804D01*
X446114Y-107180D01*
X446987Y-106305D01*
X447424Y-105139D01*
X447206Y-103388D01*
X446332Y-102513D01*
X442402Y-100763D01*
X441529Y-98721D01*
X441966Y-97263D01*
X442839Y-96388D01*
X444149Y-96097D01*
X445459Y-96388D01*
X446769Y-97263D01*
G01X461649Y-96097D02*
Y-107763D01*
G01Y-91430D02*
X461212Y-91138D01*
Y-90555D01*
X461649Y-90263D01*
X462086Y-90555D01*
Y-91138D01*
X461649Y-91430D01*
G01X476092Y-112138D02*
X477621Y-113305D01*
X479367Y-113596D01*
X480895Y-113305D01*
X482206Y-111847D01*
X483079Y-109805D01*
Y-96097D01*
G01Y-98430D02*
X482206Y-97263D01*
X480895Y-96388D01*
X479367Y-96097D01*
X477621Y-96680D01*
X476529Y-97846D01*
X475655Y-99888D01*
X475219Y-101930D01*
X475437Y-103680D01*
X476311Y-105722D01*
X477621Y-107180D01*
X479367Y-107763D01*
X480677Y-107471D01*
X482206Y-106305D01*
X483079Y-105139D01*
G01X492937Y-107763D02*
Y-96097D01*
G01Y-99013D02*
X493811Y-97555D01*
X495121Y-96388D01*
X496867Y-96097D01*
X498395Y-96388D01*
X499706Y-97555D01*
X500361Y-99596D01*
Y-107763D01*
G01X510874Y-99888D02*
X517861D01*
X517206Y-97846D01*
X516114Y-96680D01*
X514586Y-96097D01*
X513057Y-96388D01*
X511747Y-97263D01*
X510874Y-99305D01*
X510437Y-101055D01*
Y-102805D01*
X510874Y-104555D01*
X511966Y-106305D01*
X513276Y-107471D01*
X514804Y-107763D01*
X516332Y-107180D01*
X517861Y-105430D01*
G01X528592Y-107763D02*
Y-96097D01*
G01Y-98430D02*
X529684Y-97263D01*
X530776Y-96388D01*
X532304Y-96097D01*
X533395Y-96388D01*
X534706Y-97263D01*
G01X429134Y3937D02*
G03X433071Y0I3937J0D01*
G01X429134Y1964567D02*
Y3937D01*
G01X433071Y0D02*
X494095D01*
G01X421260Y3937D02*
Y1964567D01*
G01X417323Y0D02*
G03X421260Y3937I0J3937D01*
G01X429134Y11811D02*
G03X421260I-3937J0D01*
G01X429134Y3937D02*
G03X433071Y0I3937J0D01*
G01X429134Y1964567D02*
Y3937D01*
G01X433071Y0D02*
X494095D01*
G01X421260Y3937D02*
Y1964567D01*
G01X417323Y0D02*
G03X421260Y3937I0J3937D01*
G01X429134Y11811D02*
G03X421260I-3937J0D01*
G01Y42520D02*
G03X429134I3937J0D01*
G01X421260D02*
G03X429134I3937J0D01*
G01Y278740D02*
G03X421260I-3937J0D01*
G01X429134D02*
G03X421260I-3937J0D01*
G01Y309449D02*
G03X429134I3937J0D01*
G01X421260D02*
G03X429134I3937J0D01*
G01Y545669D02*
G03X421260I-3937J0D01*
G01X429134D02*
G03X421260I-3937J0D01*
G01Y576378D02*
G03X429134I3937J0D01*
G01X421260D02*
G03X429134I3937J0D01*
G01Y831496D02*
G03X421260I-3937J0D01*
G01X429134D02*
G03X421260I-3937J0D01*
G01Y862205D02*
G03X429134I3937J0D01*
G01X421260D02*
G03X429134I3937J0D01*
G01Y1106299D02*
G03X421260I-3937J0D01*
G01X429134D02*
G03X421260I-3937J0D01*
G01Y1137008D02*
G03X429134I3937J0D01*
G01X421260D02*
G03X429134I3937J0D01*
G01Y1392126D02*
G03X421260I-3937J0D01*
G01X429134D02*
G03X421260I-3937J0D01*
G01Y1422835D02*
G03X429134I3937J0D01*
G01X421260D02*
G03X429134I3937J0D01*
G01Y1659055D02*
G03X421260I-3937J0D01*
G01X429134D02*
G03X421260I-3937J0D01*
G01Y1689764D02*
G03X429134I3937J0D01*
G01X421260D02*
G03X429134I3937J0D01*
G01Y1925984D02*
G03X421260I-3937J0D01*
G01X429134D02*
G03X421260I-3937J0D01*
G01X433071Y1968504D02*
G03X429134Y1964567I0J-3937D01*
G01X494095Y1968504D02*
X433071D01*
G01X421260Y1964567D02*
G03X417323Y1968504I-3937J0D01*
G01X421260Y1956693D02*
G03X429134I3937J0D01*
G01X433071Y1968504D02*
G03X429134Y1964567I0J-3937D01*
G01X494095Y1968504D02*
X433071D01*
G01X421260Y1964567D02*
G03X417323Y1968504I-3937J0D01*
G01X421260Y1956693D02*
G03X429134I3937J0D01*
G01X433071Y1968504D02*
G03X429134Y1964567I0J-3937D01*
G01X421260D02*
G03X417323Y1968504I-3937J0D01*
G01X448096Y-152763D02*
Y-135263D01*
X452462D01*
X454209Y-136138D01*
X455519Y-137305D01*
X456611Y-139054D01*
X457484Y-141097D01*
X457702Y-144013D01*
X457484Y-146930D01*
X456611Y-148972D01*
X455519Y-150722D01*
X454209Y-151888D01*
X452462Y-152763D01*
X448096D01*
G01X470399Y-141097D02*
Y-152763D01*
G01Y-136430D02*
X469962Y-136138D01*
Y-135555D01*
X470399Y-135263D01*
X470836Y-135555D01*
Y-136138D01*
X470399Y-136430D01*
G01X487899Y-152763D02*
X486589Y-152471D01*
X485279Y-151305D01*
X484405Y-149263D01*
X483969Y-146930D01*
X484405Y-144596D01*
X485279Y-142555D01*
X486589Y-141388D01*
X487899Y-141097D01*
X489209Y-141388D01*
X490519Y-142555D01*
X491392Y-144596D01*
X491611Y-146930D01*
X491392Y-149263D01*
X490519Y-151305D01*
X489209Y-152471D01*
X487899Y-152763D01*
G01X501969Y39370D02*
G03X498032Y35433I0J-3937D01*
G01Y3937D02*
Y35433D01*
G01X494095Y0D02*
G03X498032Y3937I0J3937D01*
G01X505897Y0D02*
X648386D01*
G01X505897Y7615D02*
Y0D01*
G01X597244Y31496D02*
X505897D01*
G01Y7615D02*
G03X498023I-3937J0D01*
G01Y31496D02*
G03X505897I3937J0D01*
G01X501969Y39370D02*
G03X498032Y35433I0J-3937D01*
G01Y3937D02*
Y35433D01*
G01X494095Y0D02*
G03X498032Y3937I0J3937D01*
G01X505897Y0D02*
X620827D01*
G01X505897Y7615D02*
Y0D01*
G01X597244Y31496D02*
X505897D01*
G01Y7615D02*
G03X498023I-3937J0D01*
G01Y31496D02*
G03X505897I3937J0D01*
G01X501969Y39370D02*
X631890D01*
G01X501969D02*
X631890D01*
G01X498032Y1964567D02*
G03X494095Y1968504I-3937J0D01*
G01X498032Y1933071D02*
Y1960630D01*
G01Y1933071D02*
G03X501969Y1929134I3937J0D01*
G01X631890D02*
X501969D01*
G01X505906Y1960630D02*
Y1968504D01*
G01D02*
X648386D01*
G01X597244Y1937008D02*
X505906D01*
G01X498032Y1960630D02*
G03X505906I3937J0D01*
G01Y1937008D02*
G03X498032I-3937J0D01*
G01Y1964567D02*
G03X494095Y1968504I-3937J0D01*
G01X498032Y1933071D02*
Y1964567D01*
G01Y1933071D02*
G03X501969Y1929134I3937J0D01*
G01X631890D02*
X501969D01*
G01X505906Y1960630D02*
Y1968504D01*
G01D02*
X620827D01*
G01X597244Y1937008D02*
X505906D01*
G01X498032Y1960630D02*
G03X505906I3937J0D01*
G01Y1937008D02*
G03X498032I-3937J0D01*
G01X575349Y-152763D02*
Y-135263D01*
X572729Y-138763D01*
G01Y-152763D02*
X577969D01*
G01X588701Y-138180D02*
X590011Y-136430D01*
X591539Y-135555D01*
X593286Y-135263D01*
X595469Y-135846D01*
X596997Y-137305D01*
X597434Y-139054D01*
X597216Y-140805D01*
X596342Y-142263D01*
X591976Y-145180D01*
X590011Y-147221D01*
X588701Y-150139D01*
X588264Y-152763D01*
X597434D01*
G01X606419Y-153346D02*
X614279Y-135263D01*
G01X627849D02*
X626102Y-135846D01*
X624792Y-137305D01*
X623919Y-139054D01*
X623264Y-141388D01*
X623046Y-144013D01*
X623264Y-146638D01*
X623919Y-148972D01*
X624792Y-150722D01*
X626102Y-152180D01*
X627849Y-152763D01*
X629595Y-152180D01*
X630906Y-150722D01*
X631779Y-148972D01*
X632434Y-146638D01*
X632652Y-144013D01*
X632434Y-141388D01*
X631779Y-139054D01*
X630906Y-137305D01*
X629595Y-135846D01*
X627849Y-135263D01*
G01X644912Y-152763D02*
X645349Y-148972D01*
X646004Y-145763D01*
X646877Y-142846D01*
X647969Y-139638D01*
X649716Y-135263D01*
X640982D01*
G01X658919Y-153346D02*
X666779Y-135263D01*
G01X676201Y-138180D02*
X677511Y-136430D01*
X679039Y-135555D01*
X680786Y-135263D01*
X682969Y-135846D01*
X684497Y-137305D01*
X684934Y-139054D01*
X684716Y-140805D01*
X683842Y-142263D01*
X679476Y-145180D01*
X677511Y-147221D01*
X676201Y-150139D01*
X675764Y-152763D01*
X684934D01*
G01X697849Y-135263D02*
X696102Y-135846D01*
X694792Y-137305D01*
X693919Y-139054D01*
X693264Y-141388D01*
X693046Y-144013D01*
X693264Y-146638D01*
X693919Y-148972D01*
X694792Y-150722D01*
X696102Y-152180D01*
X697849Y-152763D01*
X699595Y-152180D01*
X700906Y-150722D01*
X701779Y-148972D01*
X702434Y-146638D01*
X702652Y-144013D01*
X702434Y-141388D01*
X701779Y-139054D01*
X700906Y-137305D01*
X699595Y-135846D01*
X697849Y-135263D01*
G01X715349Y-152763D02*
Y-135263D01*
X712729Y-138763D01*
G01Y-152763D02*
X717969D01*
G01X728701Y-138180D02*
X730011Y-136430D01*
X731539Y-135555D01*
X733286Y-135263D01*
X735469Y-135846D01*
X736997Y-137305D01*
X737434Y-139054D01*
X737216Y-140805D01*
X736342Y-142263D01*
X731976Y-145180D01*
X730011Y-147221D01*
X728701Y-150139D01*
X728264Y-152763D01*
X737434D01*
G01X623046Y-107763D02*
Y-90263D01*
X627412D01*
X629159Y-91138D01*
X630469Y-92305D01*
X631561Y-94054D01*
X632434Y-96097D01*
X632652Y-99013D01*
X632434Y-101930D01*
X631561Y-103972D01*
X630469Y-105722D01*
X629159Y-106888D01*
X627412Y-107763D01*
X623046D01*
G01X649279D02*
Y-96097D01*
G01Y-98138D02*
X648406Y-96972D01*
X647095Y-96388D01*
X645567Y-96097D01*
X644039Y-96680D01*
X642729Y-97846D01*
X641855Y-99596D01*
X641419Y-101930D01*
X641855Y-104263D01*
X642729Y-106013D01*
X644039Y-107180D01*
X645567Y-107763D01*
X647095Y-107471D01*
X648406Y-106597D01*
X649279Y-105430D01*
G01X662849Y-90263D02*
Y-107763D01*
G01X659792Y-96097D02*
X665906D01*
G01X677074Y-99888D02*
X684061D01*
X683406Y-97846D01*
X682314Y-96680D01*
X680786Y-96097D01*
X679257Y-96388D01*
X677947Y-97263D01*
X677074Y-99305D01*
X676637Y-101055D01*
Y-102805D01*
X677074Y-104555D01*
X678166Y-106305D01*
X679476Y-107471D01*
X681004Y-107763D01*
X682532Y-107180D01*
X684061Y-105430D01*
G01X635827Y31496D02*
G03X643701Y39370I0J7874D01*
G01X650689Y19685D02*
G03I-6988J0D01*
G01X635827Y31496D02*
X627953D01*
G01X597244D02*
G03Y39370I0J3937D01*
G01X627953D02*
G03Y31496I0J-3937D01*
G01X650689Y19685D02*
G03I-6988J0D01*
G01X635827Y31496D02*
X627953D01*
G01X597244D02*
G03Y39370I0J3937D01*
G01X627953D02*
G03Y31496I0J-3937D01*
G01X635827Y161417D02*
Y43307D01*
G01X631890Y39370D02*
G03X635827Y43307I0J3937D01*
G01X631890Y39370D02*
G03X635827Y43307I0J3937D01*
G01X643701Y169256D02*
G03X635827I-3937J0D01*
G01X643701D02*
G03X635827I-3937J0D01*
G01Y161417D02*
Y1807087D01*
G01Y161417D02*
Y1807087D01*
G01Y199965D02*
G03X643701I3937J0D01*
G01X635827D02*
G03X643701I3937J0D01*
G01Y436186D02*
G03X635827I-3937J0D01*
G01X643701D02*
G03X635827I-3937J0D01*
G01Y466894D02*
G03X643701I3937J0D01*
G01X635827D02*
G03X643701I3937J0D01*
G01Y703115D02*
G03X635827I-3937J0D01*
G01Y733823D02*
G03X643701I3937J0D01*
G01Y703115D02*
G03X635827I-3937J0D01*
G01Y733823D02*
G03X643701I3937J0D01*
G01X635827Y997603D02*
G03X643701I3937J0D01*
G01Y970832D02*
G03X635827I-3937J0D01*
G01Y997603D02*
G03X643701I3937J0D01*
G01Y970832D02*
G03X635827I-3937J0D01*
G01Y1265320D02*
G03X643701I3937J0D01*
G01Y1234611D02*
G03X635827I-3937J0D01*
G01Y1265320D02*
G03X643701I3937J0D01*
G01Y1234611D02*
G03X635827I-3937J0D01*
G01X643701Y1501541D02*
G03X635827I-3937J0D01*
G01X643701D02*
G03X635827I-3937J0D01*
G01Y1532249D02*
G03X643701I3937J0D01*
G01X635827D02*
G03X643701I3937J0D01*
G01Y1768470D02*
G03X635827I-3937J0D01*
G01X643701D02*
G03X635827I-3937J0D01*
G01Y1799178D02*
G03X643701I3937J0D01*
G01X635827D02*
G03X643701I3937J0D01*
G01X635827Y1818898D02*
Y1807087D01*
G01Y1818898D02*
Y1925197D01*
G01Y1818898D02*
Y1925197D01*
G01D02*
G03X631890Y1929134I-3937J0D01*
G01X635827Y1925197D02*
G03X631890Y1929134I-3937J0D01*
G01X643701D02*
G03X635827Y1937008I-7874J0D01*
G01X650689Y1948819D02*
G03I-6988J0D01*
G01X627953Y1937008D02*
X635827D01*
G01X627953D02*
G03Y1929134I0J-3937D01*
G01X597244D02*
G03Y1937008I0J3937D01*
G01X650689Y1948819D02*
G03I-6988J0D01*
G01X627953Y1937008D02*
X635827D01*
G01X627953D02*
G03Y1929134I0J-3937D01*
G01X597244D02*
G03Y1937008I0J3937D01*
G01X650689Y1948819D02*
G03I-6988J0D01*
G01X648386Y0D02*
G03X663386Y15000I0J15000D01*
G01Y1953504D02*
Y15000D01*
G01X643701Y169256D02*
Y39370D01*
G01Y436186D02*
Y199965D01*
G01Y703115D02*
Y466894D01*
G01Y970832D02*
Y733823D01*
G01Y1234611D02*
Y997603D01*
G01Y1501541D02*
Y1265320D01*
G01Y1768470D02*
Y1532249D01*
G01Y1929134D02*
Y1799178D01*
G01X663386Y1953504D02*
G03X648386Y1968504I-15000J0D01*
G01X852500Y1470050D02*
Y1939300D01*
X1336100D01*
Y1470050D01*
X852500D01*
G01Y1499900D02*
X1336100D01*
G01X852500Y1559600D02*
X1336100D01*
G01X852500Y1529750D02*
X1336100D01*
G01X852500Y1619300D02*
X1336100D01*
G01X852500Y1589450D02*
X1336100D01*
G01X852500Y1649150D02*
X1336100D01*
G01X852500Y1708850D02*
X1336100D01*
G01X852500Y1679000D02*
X1336100D01*
G01X852500Y1768550D02*
X1336100D01*
G01X852500Y1738700D02*
X1336100D01*
G01X852500Y1798400D02*
X1336100D01*
G01X863505Y1867450D02*
Y1879950D01*
X869395D01*
G01X867225Y1873908D02*
X863505D01*
G01X876990Y1879950D02*
X880710D01*
G01X878850D02*
Y1867450D01*
G01X876990D02*
X880710D01*
G01X892180Y1873700D02*
X895280D01*
Y1869950D01*
X894350Y1868700D01*
X893265Y1867867D01*
X891715Y1867450D01*
X890165Y1867867D01*
X889080Y1868700D01*
X888150Y1869950D01*
X887530Y1871408D01*
X887220Y1873075D01*
Y1874533D01*
X887530Y1875783D01*
X888150Y1877242D01*
X889080Y1878492D01*
X890010Y1879325D01*
X891250Y1879950D01*
X892335D01*
X893575Y1879533D01*
X894505Y1878700D01*
G01X900240Y1879950D02*
Y1870992D01*
X900860Y1869116D01*
X902100Y1867867D01*
X903650Y1867450D01*
X905200Y1867867D01*
X906440Y1869116D01*
X907060Y1870992D01*
Y1879950D01*
G01X912950Y1867450D02*
Y1879950D01*
X916825D01*
X918065Y1879325D01*
X918840Y1878492D01*
X919150Y1876825D01*
X918840Y1875158D01*
X917910Y1874117D01*
X916825Y1873492D01*
X912950D01*
G01X916825D02*
X919150Y1867450D01*
G01X931550D02*
X925350D01*
Y1879950D01*
X931550D01*
G01X929070Y1873908D02*
X925350D01*
G01X852500Y1858100D02*
X1336100D01*
G01X852500Y1828250D02*
X1336100D01*
G01X852500Y1914300D02*
X1336100D01*
G01X852500Y1886200D02*
X1336100D01*
G01X942400D02*
Y1470050D01*
G01X935890Y1920550D02*
Y1933050D01*
X938990D01*
X940230Y1932425D01*
X941160Y1931592D01*
X941935Y1930342D01*
X942555Y1928883D01*
X942710Y1926800D01*
X942555Y1924717D01*
X941935Y1923258D01*
X941160Y1922008D01*
X940230Y1921175D01*
X938990Y1920550D01*
X935890D01*
G01X948600D02*
Y1933050D01*
X952475D01*
X953715Y1932425D01*
X954490Y1931592D01*
X954800Y1929925D01*
X954490Y1928258D01*
X953560Y1927217D01*
X952475Y1926592D01*
X948600D01*
G01X952475D02*
X954800Y1920550D01*
G01X962240Y1933050D02*
X965960D01*
G01X964100D02*
Y1920550D01*
G01X962240D02*
X965960D01*
G01X973400Y1933050D02*
Y1920550D01*
X979600D01*
G01X985800Y1933050D02*
Y1920550D01*
X992000D01*
G01X1017110Y1932008D02*
X1016180Y1932633D01*
X1015095Y1933050D01*
X1013855D01*
X1012460Y1932425D01*
X1011375Y1931383D01*
X1010600Y1930133D01*
X1009980Y1928050D01*
X1009825Y1926175D01*
X1010135Y1924300D01*
X1010600Y1923050D01*
X1011530Y1921800D01*
X1012615Y1920967D01*
X1013700Y1920550D01*
X1014785D01*
X1015870Y1920967D01*
X1016800Y1921591D01*
X1017575Y1922425D01*
G01X1022845Y1920550D02*
Y1933050D01*
G01X1029355D02*
Y1920550D01*
G01Y1926800D02*
X1022845D01*
G01X1034625Y1920550D02*
X1038500Y1933050D01*
X1042375Y1920550D01*
G01X1040980Y1924925D02*
X1036020D01*
G01X1047800Y1920550D02*
Y1933050D01*
X1051675D01*
X1052915Y1932425D01*
X1053690Y1931592D01*
X1054000Y1929925D01*
X1053690Y1928258D01*
X1052760Y1927217D01*
X1051675Y1926592D01*
X1047800D01*
G01X1051675D02*
X1054000Y1920550D01*
G01X1063300Y1933050D02*
Y1920550D01*
G01X1059735Y1933050D02*
X1066865D01*
G01X1075700Y1920133D02*
X1075390Y1920342D01*
Y1920758D01*
X1075700Y1920967D01*
X1076010Y1920758D01*
Y1920342D01*
X1075700Y1920133D01*
G01Y1925758D02*
X1075390Y1925967D01*
Y1926383D01*
X1075700Y1926592D01*
X1076010Y1926383D01*
Y1925967D01*
X1075700Y1925758D01*
G01X1100500Y1933050D02*
Y1920550D01*
G01X1096935Y1933050D02*
X1104065D01*
G01X1112900Y1920550D02*
X1111660Y1920758D01*
X1110575Y1921591D01*
X1109645Y1922842D01*
X1109025Y1924300D01*
X1108715Y1925967D01*
Y1927633D01*
X1109025Y1929300D01*
X1109645Y1930758D01*
X1110575Y1932008D01*
X1111660Y1932842D01*
X1112900Y1933050D01*
X1114140Y1932842D01*
X1115225Y1932008D01*
X1116155Y1930758D01*
X1116775Y1929300D01*
X1117085Y1927633D01*
Y1925967D01*
X1116775Y1924300D01*
X1116155Y1922842D01*
X1115225Y1921591D01*
X1114140Y1920758D01*
X1112900Y1920550D01*
G01X1122200D02*
Y1933050D01*
X1125920D01*
X1127160Y1932425D01*
X1128090Y1930967D01*
X1128400Y1929300D01*
X1128090Y1927633D01*
X1127315Y1926383D01*
X1125920Y1925758D01*
X1122200D01*
G01X1150100Y1933050D02*
Y1920550D01*
G01X1147930Y1928883D02*
X1152270D01*
G01X1162500Y1920550D02*
X1161570Y1920758D01*
X1160640Y1921591D01*
X1160020Y1923050D01*
X1159710Y1924717D01*
X1160020Y1926383D01*
X1160640Y1927842D01*
X1161570Y1928675D01*
X1162500Y1928883D01*
X1163430Y1928675D01*
X1164360Y1927842D01*
X1164980Y1926383D01*
X1165135Y1924717D01*
X1164980Y1923050D01*
X1164360Y1921591D01*
X1163430Y1920758D01*
X1162500Y1920550D01*
G01X1188540Y1927217D02*
X1189160Y1927842D01*
X1189625Y1928883D01*
X1189935Y1930342D01*
X1189625Y1931592D01*
X1189005Y1932425D01*
X1187920Y1933050D01*
X1183735D01*
Y1920550D01*
X1188850D01*
X1189935Y1921383D01*
X1190555Y1922633D01*
X1190865Y1924092D01*
X1190555Y1925550D01*
X1189625Y1926800D01*
X1188540Y1927217D01*
X1183735D01*
G01X1199700Y1920550D02*
X1198460Y1920758D01*
X1197375Y1921591D01*
X1196445Y1922842D01*
X1195825Y1924300D01*
X1195515Y1925967D01*
Y1927633D01*
X1195825Y1929300D01*
X1196445Y1930758D01*
X1197375Y1932008D01*
X1198460Y1932842D01*
X1199700Y1933050D01*
X1200940Y1932842D01*
X1202025Y1932008D01*
X1202955Y1930758D01*
X1203575Y1929300D01*
X1203885Y1927633D01*
Y1925967D01*
X1203575Y1924300D01*
X1202955Y1922842D01*
X1202025Y1921591D01*
X1200940Y1920758D01*
X1199700Y1920550D01*
G01X1212100Y1933050D02*
Y1920550D01*
G01X1208535Y1933050D02*
X1215665D01*
G01X1224500D02*
Y1920550D01*
G01X1220935Y1933050D02*
X1228065D01*
G01X1236900Y1920550D02*
X1235660Y1920758D01*
X1234575Y1921591D01*
X1233645Y1922842D01*
X1233025Y1924300D01*
X1232715Y1925967D01*
Y1927633D01*
X1233025Y1929300D01*
X1233645Y1930758D01*
X1234575Y1932008D01*
X1235660Y1932842D01*
X1236900Y1933050D01*
X1238140Y1932842D01*
X1239225Y1932008D01*
X1240155Y1930758D01*
X1240775Y1929300D01*
X1241085Y1927633D01*
Y1925967D01*
X1240775Y1924300D01*
X1240155Y1922842D01*
X1239225Y1921591D01*
X1238140Y1920758D01*
X1236900Y1920550D01*
G01X1245270D02*
Y1933050D01*
X1249300Y1922633D01*
X1253330Y1933050D01*
Y1920550D01*
G01X966425Y1895550D02*
X970300Y1908050D01*
X974175Y1895550D01*
G01X972780Y1899925D02*
X967820D01*
G01X979600Y1908050D02*
Y1895550D01*
X985800D01*
G01X992000Y1908050D02*
Y1895550D01*
X998200D01*
G01X1016490Y1908050D02*
Y1899092D01*
X1017110Y1897216D01*
X1018350Y1895967D01*
X1019900Y1895550D01*
X1021450Y1895967D01*
X1022690Y1897216D01*
X1023310Y1899092D01*
Y1908050D01*
G01X1028735Y1895550D02*
Y1908050D01*
X1035865Y1895550D01*
Y1908050D01*
G01X1042840D02*
X1046560D01*
G01X1044700D02*
Y1895550D01*
G01X1042840D02*
X1046560D01*
G01X1057100Y1908050D02*
Y1895550D01*
G01X1053535Y1908050D02*
X1060665D01*
G01X1066245Y1897216D02*
X1067485Y1896175D01*
X1068880Y1895550D01*
X1070120D01*
X1071360Y1896175D01*
X1072290Y1897216D01*
X1072755Y1898675D01*
X1072445Y1900133D01*
X1071670Y1901383D01*
X1070275Y1902217D01*
X1068415Y1902633D01*
X1067330Y1903467D01*
X1066865Y1904925D01*
X1067175Y1906383D01*
X1067950Y1907425D01*
X1069035Y1908050D01*
X1070120D01*
X1071205Y1907633D01*
X1072135Y1906592D01*
G01X1090425Y1895550D02*
X1094300Y1908050D01*
X1098175Y1895550D01*
G01X1096780Y1899925D02*
X1091820D01*
G01X1103600Y1895550D02*
Y1908050D01*
X1107475D01*
X1108715Y1907425D01*
X1109490Y1906592D01*
X1109800Y1904925D01*
X1109490Y1903258D01*
X1108560Y1902217D01*
X1107475Y1901592D01*
X1103600D01*
G01X1107475D02*
X1109800Y1895550D01*
G01X1122200D02*
X1116000D01*
Y1908050D01*
X1122200D01*
G01X1119720Y1902008D02*
X1116000D01*
G01X1142040Y1908050D02*
X1145760D01*
G01X1143900D02*
Y1895550D01*
G01X1142040D02*
X1145760D01*
G01X1152735D02*
Y1908050D01*
X1159865Y1895550D01*
Y1908050D01*
G01X1177070Y1895550D02*
Y1908050D01*
X1181100Y1897633D01*
X1185130Y1908050D01*
Y1895550D01*
G01X1191640Y1908050D02*
X1195360D01*
G01X1193500D02*
Y1895550D01*
G01X1191640D02*
X1195360D01*
G01X1202800Y1908050D02*
Y1895550D01*
X1209000D01*
G01X1215045Y1897216D02*
X1216285Y1896175D01*
X1217680Y1895550D01*
X1218920D01*
X1220160Y1896175D01*
X1221090Y1897216D01*
X1221555Y1898675D01*
X1221245Y1900133D01*
X1220470Y1901383D01*
X1219075Y1902217D01*
X1217215Y1902633D01*
X1216130Y1903467D01*
X1215665Y1904925D01*
X1215975Y1906383D01*
X1216750Y1907425D01*
X1217835Y1908050D01*
X1218920D01*
X1220005Y1907633D01*
X1220935Y1906592D01*
G01X1012150Y1508575D02*
Y1521075D01*
X1010290Y1518575D01*
G01Y1508575D02*
X1014010D01*
G01X1026410D02*
Y1521075D01*
X1020675Y1512117D01*
X1028425D01*
G01X1036950Y1521075D02*
X1035710Y1520658D01*
X1034780Y1519617D01*
X1034160Y1518367D01*
X1033695Y1516700D01*
X1033540Y1514825D01*
X1033695Y1512950D01*
X1034160Y1511283D01*
X1034780Y1510033D01*
X1035710Y1508992D01*
X1036950Y1508575D01*
X1038190Y1508992D01*
X1039120Y1510033D01*
X1039740Y1511283D01*
X1040205Y1512950D01*
X1040360Y1514825D01*
X1040205Y1516700D01*
X1039740Y1518367D01*
X1039120Y1519617D01*
X1038190Y1520658D01*
X1036950Y1521075D01*
G01X1049350Y1508158D02*
X1049040Y1508367D01*
Y1508783D01*
X1049350Y1508992D01*
X1049660Y1508783D01*
Y1508367D01*
X1049350Y1508158D01*
G01X1061750Y1521075D02*
X1060510Y1520658D01*
X1059580Y1519617D01*
X1058960Y1518367D01*
X1058495Y1516700D01*
X1058340Y1514825D01*
X1058495Y1512950D01*
X1058960Y1511283D01*
X1059580Y1510033D01*
X1060510Y1508992D01*
X1061750Y1508575D01*
X1062990Y1508992D01*
X1063920Y1510033D01*
X1064540Y1511283D01*
X1065005Y1512950D01*
X1065160Y1514825D01*
X1065005Y1516700D01*
X1064540Y1518367D01*
X1063920Y1519617D01*
X1062990Y1520658D01*
X1061750Y1521075D01*
G01X1012150Y1478725D02*
Y1491225D01*
X1010290Y1488725D01*
G01Y1478725D02*
X1014010D01*
G01X1026410D02*
Y1491225D01*
X1020675Y1482267D01*
X1028425D01*
G01X1034005Y1489142D02*
X1034935Y1490391D01*
X1036020Y1491017D01*
X1037260Y1491225D01*
X1038810Y1490808D01*
X1039895Y1489767D01*
X1040205Y1488517D01*
X1040050Y1487266D01*
X1039430Y1486225D01*
X1036330Y1484142D01*
X1034935Y1482683D01*
X1034005Y1480600D01*
X1033695Y1478725D01*
X1040205D01*
G01X1049350Y1478308D02*
X1049040Y1478517D01*
Y1478933D01*
X1049350Y1479142D01*
X1049660Y1478933D01*
Y1478517D01*
X1049350Y1478308D01*
G01X1061750Y1491225D02*
X1060510Y1490808D01*
X1059580Y1489767D01*
X1058960Y1488517D01*
X1058495Y1486850D01*
X1058340Y1484975D01*
X1058495Y1483100D01*
X1058960Y1481433D01*
X1059580Y1480183D01*
X1060510Y1479142D01*
X1061750Y1478725D01*
X1062990Y1479142D01*
X1063920Y1480183D01*
X1064540Y1481433D01*
X1065005Y1483100D01*
X1065160Y1484975D01*
X1065005Y1486850D01*
X1064540Y1488517D01*
X1063920Y1489767D01*
X1062990Y1490808D01*
X1061750Y1491225D01*
G01X1012150Y1568275D02*
Y1580775D01*
X1010290Y1578275D01*
G01Y1568275D02*
X1014010D01*
G01X1024550D02*
Y1580775D01*
X1022690Y1578275D01*
G01Y1568275D02*
X1026410D01*
G01X1033540Y1570150D02*
X1034470Y1569108D01*
X1035555Y1568483D01*
X1036950Y1568275D01*
X1038345Y1568692D01*
X1039430Y1569525D01*
X1040205Y1570983D01*
X1040360Y1572650D01*
X1040050Y1574317D01*
X1039275Y1575358D01*
X1038190Y1576192D01*
X1037105Y1576400D01*
X1036020Y1576192D01*
X1034625Y1575358D01*
X1035090Y1580775D01*
X1039275D01*
G01X1049350Y1567858D02*
X1049040Y1568067D01*
Y1568483D01*
X1049350Y1568692D01*
X1049660Y1568483D01*
Y1568067D01*
X1049350Y1567858D01*
G01X1061750Y1580775D02*
X1060510Y1580358D01*
X1059580Y1579317D01*
X1058960Y1578067D01*
X1058495Y1576400D01*
X1058340Y1574525D01*
X1058495Y1572650D01*
X1058960Y1570983D01*
X1059580Y1569733D01*
X1060510Y1568692D01*
X1061750Y1568275D01*
X1062990Y1568692D01*
X1063920Y1569733D01*
X1064540Y1570983D01*
X1065005Y1572650D01*
X1065160Y1574525D01*
X1065005Y1576400D01*
X1064540Y1578067D01*
X1063920Y1579317D01*
X1062990Y1580358D01*
X1061750Y1580775D01*
G01X1012150Y1538425D02*
Y1550925D01*
X1010290Y1548425D01*
G01Y1538425D02*
X1014010D01*
G01X1021605Y1548842D02*
X1022535Y1550091D01*
X1023620Y1550717D01*
X1024860Y1550925D01*
X1026410Y1550508D01*
X1027495Y1549467D01*
X1027805Y1548217D01*
X1027650Y1546966D01*
X1027030Y1545925D01*
X1023930Y1543842D01*
X1022535Y1542383D01*
X1021605Y1540300D01*
X1021295Y1538425D01*
X1027805D01*
G01X1034005Y1543633D02*
X1035090Y1545092D01*
X1036020Y1545925D01*
X1037260Y1546342D01*
X1038345Y1545925D01*
X1039120Y1545092D01*
X1039740Y1543842D01*
X1039895Y1542383D01*
X1039740Y1541133D01*
X1039120Y1539883D01*
X1038190Y1538842D01*
X1037105Y1538425D01*
X1035865Y1538842D01*
X1034780Y1540091D01*
X1034160Y1541967D01*
X1034005Y1544050D01*
X1034315Y1546758D01*
X1034780Y1548217D01*
X1035555Y1549675D01*
X1036640Y1550717D01*
X1037725Y1550925D01*
X1038810Y1550508D01*
X1039585Y1549467D01*
G01X1049350Y1538008D02*
X1049040Y1538217D01*
Y1538633D01*
X1049350Y1538842D01*
X1049660Y1538633D01*
Y1538217D01*
X1049350Y1538008D01*
G01X1061750Y1550925D02*
X1060510Y1550508D01*
X1059580Y1549467D01*
X1058960Y1548217D01*
X1058495Y1546550D01*
X1058340Y1544675D01*
X1058495Y1542800D01*
X1058960Y1541133D01*
X1059580Y1539883D01*
X1060510Y1538842D01*
X1061750Y1538425D01*
X1062990Y1538842D01*
X1063920Y1539883D01*
X1064540Y1541133D01*
X1065005Y1542800D01*
X1065160Y1544675D01*
X1065005Y1546550D01*
X1064540Y1548217D01*
X1063920Y1549467D01*
X1062990Y1550508D01*
X1061750Y1550925D01*
G01X1015715Y1599583D02*
X1016800Y1598542D01*
X1018040Y1598125D01*
X1019280Y1598542D01*
X1020365Y1599791D01*
X1021140Y1601667D01*
X1021450Y1603542D01*
Y1605833D01*
X1021140Y1607708D01*
X1020365Y1609375D01*
X1019435Y1610208D01*
X1018350Y1610625D01*
X1017110Y1610208D01*
X1016180Y1609375D01*
X1015560Y1608125D01*
X1015250Y1606458D01*
X1015560Y1605000D01*
X1016335Y1603542D01*
X1017265Y1602708D01*
X1018350Y1602500D01*
X1019590Y1602916D01*
X1020520Y1603958D01*
X1021450Y1605833D01*
G01X1028115Y1599583D02*
X1029200Y1598542D01*
X1030440Y1598125D01*
X1031680Y1598542D01*
X1032765Y1599791D01*
X1033540Y1601667D01*
X1033850Y1603542D01*
Y1605833D01*
X1033540Y1607708D01*
X1032765Y1609375D01*
X1031835Y1610208D01*
X1030750Y1610625D01*
X1029510Y1610208D01*
X1028580Y1609375D01*
X1027960Y1608125D01*
X1027650Y1606458D01*
X1027960Y1605000D01*
X1028735Y1603542D01*
X1029665Y1602708D01*
X1030750Y1602500D01*
X1031990Y1602916D01*
X1032920Y1603958D01*
X1033850Y1605833D01*
G01X1043150Y1597708D02*
X1042840Y1597917D01*
Y1598333D01*
X1043150Y1598542D01*
X1043460Y1598333D01*
Y1597917D01*
X1043150Y1597708D01*
G01X1055550Y1610625D02*
X1054310Y1610208D01*
X1053380Y1609167D01*
X1052760Y1607917D01*
X1052295Y1606250D01*
X1052140Y1604375D01*
X1052295Y1602500D01*
X1052760Y1600833D01*
X1053380Y1599583D01*
X1054310Y1598542D01*
X1055550Y1598125D01*
X1056790Y1598542D01*
X1057720Y1599583D01*
X1058340Y1600833D01*
X1058805Y1602500D01*
X1058960Y1604375D01*
X1058805Y1606250D01*
X1058340Y1607917D01*
X1057720Y1609167D01*
X1056790Y1610208D01*
X1055550Y1610625D01*
G01X1012150Y1657825D02*
Y1670325D01*
X1010290Y1667825D01*
G01Y1657825D02*
X1014010D01*
G01X1021140Y1659700D02*
X1022070Y1658658D01*
X1023155Y1658033D01*
X1024550Y1657825D01*
X1025945Y1658242D01*
X1027030Y1659075D01*
X1027805Y1660533D01*
X1027960Y1662200D01*
X1027650Y1663867D01*
X1026875Y1664908D01*
X1025790Y1665742D01*
X1024705Y1665950D01*
X1023620Y1665742D01*
X1022225Y1664908D01*
X1022690Y1670325D01*
X1026875D01*
G01X1036950Y1657825D02*
X1038035Y1658033D01*
X1039275Y1658658D01*
X1040050Y1659700D01*
X1040360Y1661158D01*
X1040050Y1662616D01*
X1039120Y1663867D01*
X1037725Y1664492D01*
X1036175D01*
X1035245Y1664908D01*
X1034470Y1665950D01*
X1034160Y1667408D01*
X1034625Y1668867D01*
X1035710Y1669908D01*
X1036950Y1670325D01*
X1038190Y1669908D01*
X1039275Y1668867D01*
X1039740Y1667408D01*
X1039430Y1665950D01*
X1038655Y1664908D01*
X1037725Y1664492D01*
X1036175D01*
X1034780Y1663867D01*
X1033850Y1662616D01*
X1033540Y1661158D01*
X1033850Y1659700D01*
X1034625Y1658658D01*
X1035865Y1658033D01*
X1036950Y1657825D01*
G01X1049350Y1657408D02*
X1049040Y1657617D01*
Y1658033D01*
X1049350Y1658242D01*
X1049660Y1658033D01*
Y1657617D01*
X1049350Y1657408D01*
G01X1061750Y1670325D02*
X1060510Y1669908D01*
X1059580Y1668867D01*
X1058960Y1667617D01*
X1058495Y1665950D01*
X1058340Y1664075D01*
X1058495Y1662200D01*
X1058960Y1660533D01*
X1059580Y1659283D01*
X1060510Y1658242D01*
X1061750Y1657825D01*
X1062990Y1658242D01*
X1063920Y1659283D01*
X1064540Y1660533D01*
X1065005Y1662200D01*
X1065160Y1664075D01*
X1065005Y1665950D01*
X1064540Y1667617D01*
X1063920Y1668867D01*
X1062990Y1669908D01*
X1061750Y1670325D01*
G01X1012150Y1627975D02*
Y1640475D01*
X1010290Y1637975D01*
G01Y1627975D02*
X1014010D01*
G01X1021915Y1629433D02*
X1023000Y1628392D01*
X1024240Y1627975D01*
X1025480Y1628392D01*
X1026565Y1629641D01*
X1027340Y1631517D01*
X1027650Y1633392D01*
Y1635683D01*
X1027340Y1637558D01*
X1026565Y1639225D01*
X1025635Y1640058D01*
X1024550Y1640475D01*
X1023310Y1640058D01*
X1022380Y1639225D01*
X1021760Y1637975D01*
X1021450Y1636308D01*
X1021760Y1634850D01*
X1022535Y1633392D01*
X1023465Y1632558D01*
X1024550Y1632350D01*
X1025790Y1632766D01*
X1026720Y1633808D01*
X1027650Y1635683D01*
G01X1034315Y1629433D02*
X1035400Y1628392D01*
X1036640Y1627975D01*
X1037880Y1628392D01*
X1038965Y1629641D01*
X1039740Y1631517D01*
X1040050Y1633392D01*
Y1635683D01*
X1039740Y1637558D01*
X1038965Y1639225D01*
X1038035Y1640058D01*
X1036950Y1640475D01*
X1035710Y1640058D01*
X1034780Y1639225D01*
X1034160Y1637975D01*
X1033850Y1636308D01*
X1034160Y1634850D01*
X1034935Y1633392D01*
X1035865Y1632558D01*
X1036950Y1632350D01*
X1038190Y1632766D01*
X1039120Y1633808D01*
X1040050Y1635683D01*
G01X1049350Y1627558D02*
X1049040Y1627767D01*
Y1628183D01*
X1049350Y1628392D01*
X1049660Y1628183D01*
Y1627767D01*
X1049350Y1627558D01*
G01X1061750Y1640475D02*
X1060510Y1640058D01*
X1059580Y1639017D01*
X1058960Y1637767D01*
X1058495Y1636100D01*
X1058340Y1634225D01*
X1058495Y1632350D01*
X1058960Y1630683D01*
X1059580Y1629433D01*
X1060510Y1628392D01*
X1061750Y1627975D01*
X1062990Y1628392D01*
X1063920Y1629433D01*
X1064540Y1630683D01*
X1065005Y1632350D01*
X1065160Y1634225D01*
X1065005Y1636100D01*
X1064540Y1637767D01*
X1063920Y1639017D01*
X1062990Y1640058D01*
X1061750Y1640475D01*
G01X1020210Y1717525D02*
Y1730025D01*
X1014475Y1721067D01*
X1022225D01*
G01X1030750Y1717525D02*
Y1730025D01*
X1028890Y1727525D01*
G01Y1717525D02*
X1032610D01*
G01X1043150Y1717108D02*
X1042840Y1717317D01*
Y1717733D01*
X1043150Y1717942D01*
X1043460Y1717733D01*
Y1717317D01*
X1043150Y1717108D01*
G01X1055550Y1730025D02*
X1054310Y1729608D01*
X1053380Y1728567D01*
X1052760Y1727317D01*
X1052295Y1725650D01*
X1052140Y1723775D01*
X1052295Y1721900D01*
X1052760Y1720233D01*
X1053380Y1718983D01*
X1054310Y1717942D01*
X1055550Y1717525D01*
X1056790Y1717942D01*
X1057720Y1718983D01*
X1058340Y1720233D01*
X1058805Y1721900D01*
X1058960Y1723775D01*
X1058805Y1725650D01*
X1058340Y1727317D01*
X1057720Y1728567D01*
X1056790Y1729608D01*
X1055550Y1730025D01*
G01X1012150Y1687675D02*
Y1700175D01*
X1010290Y1697675D01*
G01Y1687675D02*
X1014010D01*
G01X1021140Y1690175D02*
X1022070Y1688716D01*
X1023310Y1687883D01*
X1024705Y1687675D01*
X1025945Y1687883D01*
X1027185Y1688925D01*
X1027960Y1690175D01*
X1028115Y1691425D01*
X1027805Y1692883D01*
X1026720Y1693925D01*
X1025635Y1694342D01*
X1024240D01*
G01X1025635D02*
X1026565Y1694967D01*
X1027340Y1696008D01*
X1027650Y1697258D01*
X1027340Y1698508D01*
X1026565Y1699550D01*
X1025170Y1700175D01*
X1023775Y1699967D01*
X1022380Y1699133D01*
G01X1036950Y1687675D02*
X1038035Y1687883D01*
X1039275Y1688508D01*
X1040050Y1689550D01*
X1040360Y1691008D01*
X1040050Y1692466D01*
X1039120Y1693717D01*
X1037725Y1694342D01*
X1036175D01*
X1035245Y1694758D01*
X1034470Y1695800D01*
X1034160Y1697258D01*
X1034625Y1698717D01*
X1035710Y1699758D01*
X1036950Y1700175D01*
X1038190Y1699758D01*
X1039275Y1698717D01*
X1039740Y1697258D01*
X1039430Y1695800D01*
X1038655Y1694758D01*
X1037725Y1694342D01*
X1036175D01*
X1034780Y1693717D01*
X1033850Y1692466D01*
X1033540Y1691008D01*
X1033850Y1689550D01*
X1034625Y1688508D01*
X1035865Y1687883D01*
X1036950Y1687675D01*
G01X1049350Y1687258D02*
X1049040Y1687467D01*
Y1687883D01*
X1049350Y1688092D01*
X1049660Y1687883D01*
Y1687467D01*
X1049350Y1687258D01*
G01X1061750Y1700175D02*
X1060510Y1699758D01*
X1059580Y1698717D01*
X1058960Y1697467D01*
X1058495Y1695800D01*
X1058340Y1693925D01*
X1058495Y1692050D01*
X1058960Y1690383D01*
X1059580Y1689133D01*
X1060510Y1688092D01*
X1061750Y1687675D01*
X1062990Y1688092D01*
X1063920Y1689133D01*
X1064540Y1690383D01*
X1065005Y1692050D01*
X1065160Y1693925D01*
X1065005Y1695800D01*
X1064540Y1697467D01*
X1063920Y1698717D01*
X1062990Y1699758D01*
X1061750Y1700175D01*
G01X1014940Y1779725D02*
X1015870Y1778266D01*
X1017110Y1777433D01*
X1018505Y1777225D01*
X1019745Y1777433D01*
X1020985Y1778475D01*
X1021760Y1779725D01*
X1021915Y1780975D01*
X1021605Y1782433D01*
X1020520Y1783475D01*
X1019435Y1783892D01*
X1018040D01*
G01X1019435D02*
X1020365Y1784517D01*
X1021140Y1785558D01*
X1021450Y1786808D01*
X1021140Y1788058D01*
X1020365Y1789100D01*
X1018970Y1789725D01*
X1017575Y1789517D01*
X1016180Y1788683D01*
G01X1027340Y1779100D02*
X1028270Y1778058D01*
X1029355Y1777433D01*
X1030750Y1777225D01*
X1032145Y1777642D01*
X1033230Y1778475D01*
X1034005Y1779933D01*
X1034160Y1781600D01*
X1033850Y1783267D01*
X1033075Y1784308D01*
X1031990Y1785142D01*
X1030905Y1785350D01*
X1029820Y1785142D01*
X1028425Y1784308D01*
X1028890Y1789725D01*
X1033075D01*
G01X1043150Y1776808D02*
X1042840Y1777017D01*
Y1777433D01*
X1043150Y1777642D01*
X1043460Y1777433D01*
Y1777017D01*
X1043150Y1776808D01*
G01X1055550Y1789725D02*
X1054310Y1789308D01*
X1053380Y1788267D01*
X1052760Y1787017D01*
X1052295Y1785350D01*
X1052140Y1783475D01*
X1052295Y1781600D01*
X1052760Y1779933D01*
X1053380Y1778683D01*
X1054310Y1777642D01*
X1055550Y1777225D01*
X1056790Y1777642D01*
X1057720Y1778683D01*
X1058340Y1779933D01*
X1058805Y1781600D01*
X1058960Y1783475D01*
X1058805Y1785350D01*
X1058340Y1787017D01*
X1057720Y1788267D01*
X1056790Y1789308D01*
X1055550Y1789725D01*
G01X1020210Y1747375D02*
Y1759875D01*
X1014475Y1750917D01*
X1022225D01*
G01X1030750Y1759875D02*
X1029510Y1759458D01*
X1028580Y1758417D01*
X1027960Y1757167D01*
X1027495Y1755500D01*
X1027340Y1753625D01*
X1027495Y1751750D01*
X1027960Y1750083D01*
X1028580Y1748833D01*
X1029510Y1747792D01*
X1030750Y1747375D01*
X1031990Y1747792D01*
X1032920Y1748833D01*
X1033540Y1750083D01*
X1034005Y1751750D01*
X1034160Y1753625D01*
X1034005Y1755500D01*
X1033540Y1757167D01*
X1032920Y1758417D01*
X1031990Y1759458D01*
X1030750Y1759875D01*
G01X1043150Y1746958D02*
X1042840Y1747167D01*
Y1747583D01*
X1043150Y1747792D01*
X1043460Y1747583D01*
Y1747167D01*
X1043150Y1746958D01*
G01X1055550Y1759875D02*
X1054310Y1759458D01*
X1053380Y1758417D01*
X1052760Y1757167D01*
X1052295Y1755500D01*
X1052140Y1753625D01*
X1052295Y1751750D01*
X1052760Y1750083D01*
X1053380Y1748833D01*
X1054310Y1747792D01*
X1055550Y1747375D01*
X1056790Y1747792D01*
X1057720Y1748833D01*
X1058340Y1750083D01*
X1058805Y1751750D01*
X1058960Y1753625D01*
X1058805Y1755500D01*
X1058340Y1757167D01*
X1057720Y1758417D01*
X1056790Y1759458D01*
X1055550Y1759875D01*
G01X1018350Y1807075D02*
Y1819575D01*
X1016490Y1817075D01*
G01Y1807075D02*
X1020210D01*
G01X1027805Y1812283D02*
X1028890Y1813742D01*
X1029820Y1814575D01*
X1031060Y1814992D01*
X1032145Y1814575D01*
X1032920Y1813742D01*
X1033540Y1812492D01*
X1033695Y1811033D01*
X1033540Y1809783D01*
X1032920Y1808533D01*
X1031990Y1807492D01*
X1030905Y1807075D01*
X1029665Y1807492D01*
X1028580Y1808741D01*
X1027960Y1810617D01*
X1027805Y1812700D01*
X1028115Y1815408D01*
X1028580Y1816867D01*
X1029355Y1818325D01*
X1030440Y1819367D01*
X1031525Y1819575D01*
X1032610Y1819158D01*
X1033385Y1818117D01*
G01X1043150Y1806658D02*
X1042840Y1806867D01*
Y1807283D01*
X1043150Y1807492D01*
X1043460Y1807283D01*
Y1806867D01*
X1043150Y1806658D01*
G01X1055550Y1819575D02*
X1054310Y1819158D01*
X1053380Y1818117D01*
X1052760Y1816867D01*
X1052295Y1815200D01*
X1052140Y1813325D01*
X1052295Y1811450D01*
X1052760Y1809783D01*
X1053380Y1808533D01*
X1054310Y1807492D01*
X1055550Y1807075D01*
X1056790Y1807492D01*
X1057720Y1808533D01*
X1058340Y1809783D01*
X1058805Y1811450D01*
X1058960Y1813325D01*
X1058805Y1815200D01*
X1058340Y1816867D01*
X1057720Y1818117D01*
X1056790Y1819158D01*
X1055550Y1819575D01*
G01X1015095Y1869116D02*
X1016335Y1868075D01*
X1017730Y1867450D01*
X1018970D01*
X1020210Y1868075D01*
X1021140Y1869116D01*
X1021605Y1870575D01*
X1021295Y1872033D01*
X1020520Y1873283D01*
X1019125Y1874117D01*
X1017265Y1874533D01*
X1016180Y1875367D01*
X1015715Y1876825D01*
X1016025Y1878283D01*
X1016800Y1879325D01*
X1017885Y1879950D01*
X1018970D01*
X1020055Y1879533D01*
X1020985Y1878492D01*
G01X1028890Y1879950D02*
X1032610D01*
G01X1030750D02*
Y1867450D01*
G01X1028890D02*
X1032610D01*
G01X1040205Y1879950D02*
X1046095D01*
X1040205Y1867450D01*
X1046095D01*
G01X1058650D02*
X1052450D01*
Y1879950D01*
X1058650D01*
G01X1056170Y1873908D02*
X1052450D01*
G01X1018350Y1836925D02*
Y1849425D01*
X1016490Y1846925D01*
G01Y1836925D02*
X1020210D01*
G01X1027805Y1847342D02*
X1028735Y1848591D01*
X1029820Y1849217D01*
X1031060Y1849425D01*
X1032610Y1849008D01*
X1033695Y1847967D01*
X1034005Y1846717D01*
X1033850Y1845466D01*
X1033230Y1844425D01*
X1030130Y1842342D01*
X1028735Y1840883D01*
X1027805Y1838800D01*
X1027495Y1836925D01*
X1034005D01*
G01X1043150Y1836508D02*
X1042840Y1836717D01*
Y1837133D01*
X1043150Y1837342D01*
X1043460Y1837133D01*
Y1836717D01*
X1043150Y1836508D01*
G01X1055550Y1849425D02*
X1054310Y1849008D01*
X1053380Y1847967D01*
X1052760Y1846717D01*
X1052295Y1845050D01*
X1052140Y1843175D01*
X1052295Y1841300D01*
X1052760Y1839633D01*
X1053380Y1838383D01*
X1054310Y1837342D01*
X1055550Y1836925D01*
X1056790Y1837342D01*
X1057720Y1838383D01*
X1058340Y1839633D01*
X1058805Y1841300D01*
X1058960Y1843175D01*
X1058805Y1845050D01*
X1058340Y1846717D01*
X1057720Y1847967D01*
X1056790Y1849008D01*
X1055550Y1849425D01*
G01X1135685Y1508575D02*
Y1521075D01*
X1142815Y1508575D01*
Y1521075D01*
G01X1151650Y1508575D02*
X1150410Y1508783D01*
X1149325Y1509616D01*
X1148395Y1510867D01*
X1147775Y1512325D01*
X1147465Y1513992D01*
Y1515658D01*
X1147775Y1517325D01*
X1148395Y1518783D01*
X1149325Y1520033D01*
X1150410Y1520867D01*
X1151650Y1521075D01*
X1152890Y1520867D01*
X1153975Y1520033D01*
X1154905Y1518783D01*
X1155525Y1517325D01*
X1155835Y1515658D01*
Y1513992D01*
X1155525Y1512325D01*
X1154905Y1510867D01*
X1153975Y1509616D01*
X1152890Y1508783D01*
X1151650Y1508575D01*
G01X1160485D02*
Y1521075D01*
X1167615Y1508575D01*
Y1521075D01*
G01X1174435Y1512742D02*
X1178465D01*
G01X1185750Y1508575D02*
Y1521075D01*
X1189470D01*
X1190710Y1520450D01*
X1191640Y1518992D01*
X1191950Y1517325D01*
X1191640Y1515658D01*
X1190865Y1514408D01*
X1189470Y1513783D01*
X1185750D01*
G01X1198150Y1521075D02*
Y1508575D01*
X1204350D01*
G01X1209775D02*
X1213650Y1521075D01*
X1217525Y1508575D01*
G01X1216130Y1512950D02*
X1211170D01*
G01X1226050Y1521075D02*
Y1508575D01*
G01X1222485Y1521075D02*
X1229615D01*
G01X1241550Y1508575D02*
X1235350D01*
Y1521075D01*
X1241550D01*
G01X1239070Y1515033D02*
X1235350D01*
G01X1247440Y1508575D02*
Y1521075D01*
X1250540D01*
X1251780Y1520450D01*
X1252710Y1519617D01*
X1253485Y1518367D01*
X1254105Y1516908D01*
X1254260Y1514825D01*
X1254105Y1512742D01*
X1253485Y1511283D01*
X1252710Y1510033D01*
X1251780Y1509200D01*
X1250540Y1508575D01*
X1247440D01*
G01X1135685Y1478725D02*
Y1491225D01*
X1142815Y1478725D01*
Y1491225D01*
G01X1151650Y1478725D02*
X1150410Y1478933D01*
X1149325Y1479766D01*
X1148395Y1481017D01*
X1147775Y1482475D01*
X1147465Y1484142D01*
Y1485808D01*
X1147775Y1487475D01*
X1148395Y1488933D01*
X1149325Y1490183D01*
X1150410Y1491017D01*
X1151650Y1491225D01*
X1152890Y1491017D01*
X1153975Y1490183D01*
X1154905Y1488933D01*
X1155525Y1487475D01*
X1155835Y1485808D01*
Y1484142D01*
X1155525Y1482475D01*
X1154905Y1481017D01*
X1153975Y1479766D01*
X1152890Y1478933D01*
X1151650Y1478725D01*
G01X1160485D02*
Y1491225D01*
X1167615Y1478725D01*
Y1491225D01*
G01X1174435Y1482892D02*
X1178465D01*
G01X1185750Y1478725D02*
Y1491225D01*
X1189470D01*
X1190710Y1490600D01*
X1191640Y1489142D01*
X1191950Y1487475D01*
X1191640Y1485808D01*
X1190865Y1484558D01*
X1189470Y1483933D01*
X1185750D01*
G01X1198150Y1491225D02*
Y1478725D01*
X1204350D01*
G01X1209775D02*
X1213650Y1491225D01*
X1217525Y1478725D01*
G01X1216130Y1483100D02*
X1211170D01*
G01X1226050Y1491225D02*
Y1478725D01*
G01X1222485Y1491225D02*
X1229615D01*
G01X1241550Y1478725D02*
X1235350D01*
Y1491225D01*
X1241550D01*
G01X1239070Y1485183D02*
X1235350D01*
G01X1247440Y1478725D02*
Y1491225D01*
X1250540D01*
X1251780Y1490600D01*
X1252710Y1489767D01*
X1253485Y1488517D01*
X1254105Y1487058D01*
X1254260Y1484975D01*
X1254105Y1482892D01*
X1253485Y1481433D01*
X1252710Y1480183D01*
X1251780Y1479350D01*
X1250540Y1478725D01*
X1247440D01*
G01X1131500Y1886200D02*
Y1470050D01*
G01X1135685Y1568275D02*
Y1580775D01*
X1142815Y1568275D01*
Y1580775D01*
G01X1151650Y1568275D02*
X1150410Y1568483D01*
X1149325Y1569316D01*
X1148395Y1570567D01*
X1147775Y1572025D01*
X1147465Y1573692D01*
Y1575358D01*
X1147775Y1577025D01*
X1148395Y1578483D01*
X1149325Y1579733D01*
X1150410Y1580567D01*
X1151650Y1580775D01*
X1152890Y1580567D01*
X1153975Y1579733D01*
X1154905Y1578483D01*
X1155525Y1577025D01*
X1155835Y1575358D01*
Y1573692D01*
X1155525Y1572025D01*
X1154905Y1570567D01*
X1153975Y1569316D01*
X1152890Y1568483D01*
X1151650Y1568275D01*
G01X1160485D02*
Y1580775D01*
X1167615Y1568275D01*
Y1580775D01*
G01X1174435Y1572442D02*
X1178465D01*
G01X1185750Y1568275D02*
Y1580775D01*
X1189470D01*
X1190710Y1580150D01*
X1191640Y1578692D01*
X1191950Y1577025D01*
X1191640Y1575358D01*
X1190865Y1574108D01*
X1189470Y1573483D01*
X1185750D01*
G01X1198150Y1580775D02*
Y1568275D01*
X1204350D01*
G01X1209775D02*
X1213650Y1580775D01*
X1217525Y1568275D01*
G01X1216130Y1572650D02*
X1211170D01*
G01X1226050Y1580775D02*
Y1568275D01*
G01X1222485Y1580775D02*
X1229615D01*
G01X1241550Y1568275D02*
X1235350D01*
Y1580775D01*
X1241550D01*
G01X1239070Y1574733D02*
X1235350D01*
G01X1247440Y1568275D02*
Y1580775D01*
X1250540D01*
X1251780Y1580150D01*
X1252710Y1579317D01*
X1253485Y1578067D01*
X1254105Y1576608D01*
X1254260Y1574525D01*
X1254105Y1572442D01*
X1253485Y1570983D01*
X1252710Y1569733D01*
X1251780Y1568900D01*
X1250540Y1568275D01*
X1247440D01*
G01X1135685Y1538425D02*
Y1550925D01*
X1142815Y1538425D01*
Y1550925D01*
G01X1151650Y1538425D02*
X1150410Y1538633D01*
X1149325Y1539466D01*
X1148395Y1540717D01*
X1147775Y1542175D01*
X1147465Y1543842D01*
Y1545508D01*
X1147775Y1547175D01*
X1148395Y1548633D01*
X1149325Y1549883D01*
X1150410Y1550717D01*
X1151650Y1550925D01*
X1152890Y1550717D01*
X1153975Y1549883D01*
X1154905Y1548633D01*
X1155525Y1547175D01*
X1155835Y1545508D01*
Y1543842D01*
X1155525Y1542175D01*
X1154905Y1540717D01*
X1153975Y1539466D01*
X1152890Y1538633D01*
X1151650Y1538425D01*
G01X1160485D02*
Y1550925D01*
X1167615Y1538425D01*
Y1550925D01*
G01X1174435Y1542592D02*
X1178465D01*
G01X1185750Y1538425D02*
Y1550925D01*
X1189470D01*
X1190710Y1550300D01*
X1191640Y1548842D01*
X1191950Y1547175D01*
X1191640Y1545508D01*
X1190865Y1544258D01*
X1189470Y1543633D01*
X1185750D01*
G01X1198150Y1550925D02*
Y1538425D01*
X1204350D01*
G01X1209775D02*
X1213650Y1550925D01*
X1217525Y1538425D01*
G01X1216130Y1542800D02*
X1211170D01*
G01X1226050Y1550925D02*
Y1538425D01*
G01X1222485Y1550925D02*
X1229615D01*
G01X1241550Y1538425D02*
X1235350D01*
Y1550925D01*
X1241550D01*
G01X1239070Y1544883D02*
X1235350D01*
G01X1247440Y1538425D02*
Y1550925D01*
X1250540D01*
X1251780Y1550300D01*
X1252710Y1549467D01*
X1253485Y1548217D01*
X1254105Y1546758D01*
X1254260Y1544675D01*
X1254105Y1542592D01*
X1253485Y1541133D01*
X1252710Y1539883D01*
X1251780Y1539050D01*
X1250540Y1538425D01*
X1247440D01*
G01X1135685Y1598125D02*
Y1610625D01*
X1142815Y1598125D01*
Y1610625D01*
G01X1151650Y1598125D02*
X1150410Y1598333D01*
X1149325Y1599166D01*
X1148395Y1600417D01*
X1147775Y1601875D01*
X1147465Y1603542D01*
Y1605208D01*
X1147775Y1606875D01*
X1148395Y1608333D01*
X1149325Y1609583D01*
X1150410Y1610417D01*
X1151650Y1610625D01*
X1152890Y1610417D01*
X1153975Y1609583D01*
X1154905Y1608333D01*
X1155525Y1606875D01*
X1155835Y1605208D01*
Y1603542D01*
X1155525Y1601875D01*
X1154905Y1600417D01*
X1153975Y1599166D01*
X1152890Y1598333D01*
X1151650Y1598125D01*
G01X1160485D02*
Y1610625D01*
X1167615Y1598125D01*
Y1610625D01*
G01X1174435Y1602292D02*
X1178465D01*
G01X1185750Y1598125D02*
Y1610625D01*
X1189470D01*
X1190710Y1610000D01*
X1191640Y1608542D01*
X1191950Y1606875D01*
X1191640Y1605208D01*
X1190865Y1603958D01*
X1189470Y1603333D01*
X1185750D01*
G01X1198150Y1610625D02*
Y1598125D01*
X1204350D01*
G01X1209775D02*
X1213650Y1610625D01*
X1217525Y1598125D01*
G01X1216130Y1602500D02*
X1211170D01*
G01X1226050Y1610625D02*
Y1598125D01*
G01X1222485Y1610625D02*
X1229615D01*
G01X1241550Y1598125D02*
X1235350D01*
Y1610625D01*
X1241550D01*
G01X1239070Y1604583D02*
X1235350D01*
G01X1247440Y1598125D02*
Y1610625D01*
X1250540D01*
X1251780Y1610000D01*
X1252710Y1609167D01*
X1253485Y1607917D01*
X1254105Y1606458D01*
X1254260Y1604375D01*
X1254105Y1602292D01*
X1253485Y1600833D01*
X1252710Y1599583D01*
X1251780Y1598750D01*
X1250540Y1598125D01*
X1247440D01*
G01X1160950Y1657825D02*
Y1670325D01*
X1164670D01*
X1165910Y1669700D01*
X1166840Y1668242D01*
X1167150Y1666575D01*
X1166840Y1664908D01*
X1166065Y1663658D01*
X1164670Y1663033D01*
X1160950D01*
G01X1173350Y1670325D02*
Y1657825D01*
X1179550D01*
G01X1184975D02*
X1188850Y1670325D01*
X1192725Y1657825D01*
G01X1191330Y1662200D02*
X1186370D01*
G01X1201250Y1670325D02*
Y1657825D01*
G01X1197685Y1670325D02*
X1204815D01*
G01X1216750Y1657825D02*
X1210550D01*
Y1670325D01*
X1216750D01*
G01X1214270Y1664283D02*
X1210550D01*
G01X1222640Y1657825D02*
Y1670325D01*
X1225740D01*
X1226980Y1669700D01*
X1227910Y1668867D01*
X1228685Y1667617D01*
X1229305Y1666158D01*
X1229460Y1664075D01*
X1229305Y1661992D01*
X1228685Y1660533D01*
X1227910Y1659283D01*
X1226980Y1658450D01*
X1225740Y1657825D01*
X1222640D01*
G01X1160950Y1627975D02*
Y1640475D01*
X1164670D01*
X1165910Y1639850D01*
X1166840Y1638392D01*
X1167150Y1636725D01*
X1166840Y1635058D01*
X1166065Y1633808D01*
X1164670Y1633183D01*
X1160950D01*
G01X1173350Y1640475D02*
Y1627975D01*
X1179550D01*
G01X1184975D02*
X1188850Y1640475D01*
X1192725Y1627975D01*
G01X1191330Y1632350D02*
X1186370D01*
G01X1201250Y1640475D02*
Y1627975D01*
G01X1197685Y1640475D02*
X1204815D01*
G01X1216750Y1627975D02*
X1210550D01*
Y1640475D01*
X1216750D01*
G01X1214270Y1634433D02*
X1210550D01*
G01X1222640Y1627975D02*
Y1640475D01*
X1225740D01*
X1226980Y1639850D01*
X1227910Y1639017D01*
X1228685Y1637767D01*
X1229305Y1636308D01*
X1229460Y1634225D01*
X1229305Y1632142D01*
X1228685Y1630683D01*
X1227910Y1629433D01*
X1226980Y1628600D01*
X1225740Y1627975D01*
X1222640D01*
G01X1160950Y1717525D02*
Y1730025D01*
X1164670D01*
X1165910Y1729400D01*
X1166840Y1727942D01*
X1167150Y1726275D01*
X1166840Y1724608D01*
X1166065Y1723358D01*
X1164670Y1722733D01*
X1160950D01*
G01X1173350Y1730025D02*
Y1717525D01*
X1179550D01*
G01X1184975D02*
X1188850Y1730025D01*
X1192725Y1717525D01*
G01X1191330Y1721900D02*
X1186370D01*
G01X1201250Y1730025D02*
Y1717525D01*
G01X1197685Y1730025D02*
X1204815D01*
G01X1216750Y1717525D02*
X1210550D01*
Y1730025D01*
X1216750D01*
G01X1214270Y1723983D02*
X1210550D01*
G01X1222640Y1717525D02*
Y1730025D01*
X1225740D01*
X1226980Y1729400D01*
X1227910Y1728567D01*
X1228685Y1727317D01*
X1229305Y1725858D01*
X1229460Y1723775D01*
X1229305Y1721692D01*
X1228685Y1720233D01*
X1227910Y1718983D01*
X1226980Y1718150D01*
X1225740Y1717525D01*
X1222640D01*
G01X1160950Y1687675D02*
Y1700175D01*
X1164670D01*
X1165910Y1699550D01*
X1166840Y1698092D01*
X1167150Y1696425D01*
X1166840Y1694758D01*
X1166065Y1693508D01*
X1164670Y1692883D01*
X1160950D01*
G01X1173350Y1700175D02*
Y1687675D01*
X1179550D01*
G01X1184975D02*
X1188850Y1700175D01*
X1192725Y1687675D01*
G01X1191330Y1692050D02*
X1186370D01*
G01X1201250Y1700175D02*
Y1687675D01*
G01X1197685Y1700175D02*
X1204815D01*
G01X1216750Y1687675D02*
X1210550D01*
Y1700175D01*
X1216750D01*
G01X1214270Y1694133D02*
X1210550D01*
G01X1222640Y1687675D02*
Y1700175D01*
X1225740D01*
X1226980Y1699550D01*
X1227910Y1698717D01*
X1228685Y1697467D01*
X1229305Y1696008D01*
X1229460Y1693925D01*
X1229305Y1691842D01*
X1228685Y1690383D01*
X1227910Y1689133D01*
X1226980Y1688300D01*
X1225740Y1687675D01*
X1222640D01*
G01X1160950Y1777225D02*
Y1789725D01*
X1164670D01*
X1165910Y1789100D01*
X1166840Y1787642D01*
X1167150Y1785975D01*
X1166840Y1784308D01*
X1166065Y1783058D01*
X1164670Y1782433D01*
X1160950D01*
G01X1173350Y1789725D02*
Y1777225D01*
X1179550D01*
G01X1184975D02*
X1188850Y1789725D01*
X1192725Y1777225D01*
G01X1191330Y1781600D02*
X1186370D01*
G01X1201250Y1789725D02*
Y1777225D01*
G01X1197685Y1789725D02*
X1204815D01*
G01X1216750Y1777225D02*
X1210550D01*
Y1789725D01*
X1216750D01*
G01X1214270Y1783683D02*
X1210550D01*
G01X1222640Y1777225D02*
Y1789725D01*
X1225740D01*
X1226980Y1789100D01*
X1227910Y1788267D01*
X1228685Y1787017D01*
X1229305Y1785558D01*
X1229460Y1783475D01*
X1229305Y1781392D01*
X1228685Y1779933D01*
X1227910Y1778683D01*
X1226980Y1777850D01*
X1225740Y1777225D01*
X1222640D01*
G01X1160950Y1747375D02*
Y1759875D01*
X1164670D01*
X1165910Y1759250D01*
X1166840Y1757792D01*
X1167150Y1756125D01*
X1166840Y1754458D01*
X1166065Y1753208D01*
X1164670Y1752583D01*
X1160950D01*
G01X1173350Y1759875D02*
Y1747375D01*
X1179550D01*
G01X1184975D02*
X1188850Y1759875D01*
X1192725Y1747375D01*
G01X1191330Y1751750D02*
X1186370D01*
G01X1201250Y1759875D02*
Y1747375D01*
G01X1197685Y1759875D02*
X1204815D01*
G01X1216750Y1747375D02*
X1210550D01*
Y1759875D01*
X1216750D01*
G01X1214270Y1753833D02*
X1210550D01*
G01X1222640Y1747375D02*
Y1759875D01*
X1225740D01*
X1226980Y1759250D01*
X1227910Y1758417D01*
X1228685Y1757167D01*
X1229305Y1755708D01*
X1229460Y1753625D01*
X1229305Y1751542D01*
X1228685Y1750083D01*
X1227910Y1748833D01*
X1226980Y1748000D01*
X1225740Y1747375D01*
X1222640D01*
G01X1160950Y1807075D02*
Y1819575D01*
X1164670D01*
X1165910Y1818950D01*
X1166840Y1817492D01*
X1167150Y1815825D01*
X1166840Y1814158D01*
X1166065Y1812908D01*
X1164670Y1812283D01*
X1160950D01*
G01X1173350Y1819575D02*
Y1807075D01*
X1179550D01*
G01X1184975D02*
X1188850Y1819575D01*
X1192725Y1807075D01*
G01X1191330Y1811450D02*
X1186370D01*
G01X1201250Y1819575D02*
Y1807075D01*
G01X1197685Y1819575D02*
X1204815D01*
G01X1216750Y1807075D02*
X1210550D01*
Y1819575D01*
X1216750D01*
G01X1214270Y1813533D02*
X1210550D01*
G01X1222640Y1807075D02*
Y1819575D01*
X1225740D01*
X1226980Y1818950D01*
X1227910Y1818117D01*
X1228685Y1816867D01*
X1229305Y1815408D01*
X1229460Y1813325D01*
X1229305Y1811242D01*
X1228685Y1809783D01*
X1227910Y1808533D01*
X1226980Y1807700D01*
X1225740Y1807075D01*
X1222640D01*
G01X1160950Y1867450D02*
Y1879950D01*
X1164670D01*
X1165910Y1879325D01*
X1166840Y1877867D01*
X1167150Y1876200D01*
X1166840Y1874533D01*
X1166065Y1873283D01*
X1164670Y1872658D01*
X1160950D01*
G01X1173350Y1879950D02*
Y1867450D01*
X1179550D01*
G01X1184975D02*
X1188850Y1879950D01*
X1192725Y1867450D01*
G01X1191330Y1871825D02*
X1186370D01*
G01X1201250Y1879950D02*
Y1867450D01*
G01X1197685Y1879950D02*
X1204815D01*
G01X1216750Y1867450D02*
X1210550D01*
Y1879950D01*
X1216750D01*
G01X1214270Y1873908D02*
X1210550D01*
G01X1222640Y1867450D02*
Y1879950D01*
X1225740D01*
X1226980Y1879325D01*
X1227910Y1878492D01*
X1228685Y1877242D01*
X1229305Y1875783D01*
X1229460Y1873700D01*
X1229305Y1871617D01*
X1228685Y1870158D01*
X1227910Y1868908D01*
X1226980Y1868075D01*
X1225740Y1867450D01*
X1222640D01*
G01X1160950Y1836925D02*
Y1849425D01*
X1164670D01*
X1165910Y1848800D01*
X1166840Y1847342D01*
X1167150Y1845675D01*
X1166840Y1844008D01*
X1166065Y1842758D01*
X1164670Y1842133D01*
X1160950D01*
G01X1173350Y1849425D02*
Y1836925D01*
X1179550D01*
G01X1184975D02*
X1188850Y1849425D01*
X1192725Y1836925D01*
G01X1191330Y1841300D02*
X1186370D01*
G01X1201250Y1849425D02*
Y1836925D01*
G01X1197685Y1849425D02*
X1204815D01*
G01X1216750Y1836925D02*
X1210550D01*
Y1849425D01*
X1216750D01*
G01X1214270Y1843383D02*
X1210550D01*
G01X1222640Y1836925D02*
Y1849425D01*
X1225740D01*
X1226980Y1848800D01*
X1227910Y1847967D01*
X1228685Y1846717D01*
X1229305Y1845258D01*
X1229460Y1843175D01*
X1229305Y1841092D01*
X1228685Y1839633D01*
X1227910Y1838383D01*
X1226980Y1837550D01*
X1225740Y1836925D01*
X1222640D01*
G01X1299210Y1508575D02*
Y1521075D01*
X1293475Y1512117D01*
X1301225D01*
G01X1291150Y1478725D02*
Y1491225D01*
X1289290Y1488725D01*
G01Y1478725D02*
X1293010D01*
G01X1300605Y1489142D02*
X1301535Y1490391D01*
X1302620Y1491017D01*
X1303860Y1491225D01*
X1305410Y1490808D01*
X1306495Y1489767D01*
X1306805Y1488517D01*
X1306650Y1487266D01*
X1306030Y1486225D01*
X1302930Y1484142D01*
X1301535Y1482683D01*
X1300605Y1480600D01*
X1300295Y1478725D01*
X1306805D01*
G01X1258600Y1886200D02*
Y1470050D01*
G01X1294405Y1573483D02*
X1295490Y1574942D01*
X1296420Y1575775D01*
X1297660Y1576192D01*
X1298745Y1575775D01*
X1299520Y1574942D01*
X1300140Y1573692D01*
X1300295Y1572233D01*
X1300140Y1570983D01*
X1299520Y1569733D01*
X1298590Y1568692D01*
X1297505Y1568275D01*
X1296265Y1568692D01*
X1295180Y1569941D01*
X1294560Y1571817D01*
X1294405Y1573900D01*
X1294715Y1576608D01*
X1295180Y1578067D01*
X1295955Y1579525D01*
X1297040Y1580567D01*
X1298125Y1580775D01*
X1299210Y1580358D01*
X1299985Y1579317D01*
G01X1299210Y1538425D02*
Y1550925D01*
X1293475Y1541967D01*
X1301225D01*
G01X1299210Y1598125D02*
Y1610625D01*
X1293475Y1601667D01*
X1301225D01*
G01X1294405Y1668242D02*
X1295335Y1669491D01*
X1296420Y1670117D01*
X1297660Y1670325D01*
X1299210Y1669908D01*
X1300295Y1668867D01*
X1300605Y1667617D01*
X1300450Y1666366D01*
X1299830Y1665325D01*
X1296730Y1663242D01*
X1295335Y1661783D01*
X1294405Y1659700D01*
X1294095Y1657825D01*
X1300605D01*
G01X1293940Y1629850D02*
X1294870Y1628808D01*
X1295955Y1628183D01*
X1297350Y1627975D01*
X1298745Y1628392D01*
X1299830Y1629225D01*
X1300605Y1630683D01*
X1300760Y1632350D01*
X1300450Y1634017D01*
X1299675Y1635058D01*
X1298590Y1635892D01*
X1297505Y1636100D01*
X1296420Y1635892D01*
X1295025Y1635058D01*
X1295490Y1640475D01*
X1299675D01*
G01X1284950Y1717525D02*
Y1730025D01*
X1283090Y1727525D01*
G01Y1717525D02*
X1286810D01*
G01X1297350Y1730025D02*
X1296110Y1729608D01*
X1295180Y1728567D01*
X1294560Y1727317D01*
X1294095Y1725650D01*
X1293940Y1723775D01*
X1294095Y1721900D01*
X1294560Y1720233D01*
X1295180Y1718983D01*
X1296110Y1717942D01*
X1297350Y1717525D01*
X1298590Y1717942D01*
X1299520Y1718983D01*
X1300140Y1720233D01*
X1300605Y1721900D01*
X1300760Y1723775D01*
X1300605Y1725650D01*
X1300140Y1727317D01*
X1299520Y1728567D01*
X1298590Y1729608D01*
X1297350Y1730025D01*
G01X1311610Y1717525D02*
Y1730025D01*
X1305875Y1721067D01*
X1313625D01*
G01X1294405Y1692883D02*
X1295490Y1694342D01*
X1296420Y1695175D01*
X1297660Y1695592D01*
X1298745Y1695175D01*
X1299520Y1694342D01*
X1300140Y1693092D01*
X1300295Y1691633D01*
X1300140Y1690383D01*
X1299520Y1689133D01*
X1298590Y1688092D01*
X1297505Y1687675D01*
X1296265Y1688092D01*
X1295180Y1689341D01*
X1294560Y1691217D01*
X1294405Y1693300D01*
X1294715Y1696008D01*
X1295180Y1697467D01*
X1295955Y1698925D01*
X1297040Y1699967D01*
X1298125Y1700175D01*
X1299210Y1699758D01*
X1299985Y1698717D01*
G01X1291150Y1777225D02*
Y1789725D01*
X1289290Y1787225D01*
G01Y1777225D02*
X1293010D01*
G01X1303550D02*
X1304635Y1777433D01*
X1305875Y1778058D01*
X1306650Y1779100D01*
X1306960Y1780558D01*
X1306650Y1782016D01*
X1305720Y1783267D01*
X1304325Y1783892D01*
X1302775D01*
X1301845Y1784308D01*
X1301070Y1785350D01*
X1300760Y1786808D01*
X1301225Y1788267D01*
X1302310Y1789308D01*
X1303550Y1789725D01*
X1304790Y1789308D01*
X1305875Y1788267D01*
X1306340Y1786808D01*
X1306030Y1785350D01*
X1305255Y1784308D01*
X1304325Y1783892D01*
X1302775D01*
X1301380Y1783267D01*
X1300450Y1782016D01*
X1300140Y1780558D01*
X1300450Y1779100D01*
X1301225Y1778058D01*
X1302465Y1777433D01*
X1303550Y1777225D01*
G01X1287740Y1749875D02*
X1288670Y1748416D01*
X1289910Y1747583D01*
X1291305Y1747375D01*
X1292545Y1747583D01*
X1293785Y1748625D01*
X1294560Y1749875D01*
X1294715Y1751125D01*
X1294405Y1752583D01*
X1293320Y1753625D01*
X1292235Y1754042D01*
X1290840D01*
G01X1292235D02*
X1293165Y1754667D01*
X1293940Y1755708D01*
X1294250Y1756958D01*
X1293940Y1758208D01*
X1293165Y1759250D01*
X1291770Y1759875D01*
X1290375Y1759667D01*
X1288980Y1758833D01*
G01X1300605Y1752583D02*
X1301690Y1754042D01*
X1302620Y1754875D01*
X1303860Y1755292D01*
X1304945Y1754875D01*
X1305720Y1754042D01*
X1306340Y1752792D01*
X1306495Y1751333D01*
X1306340Y1750083D01*
X1305720Y1748833D01*
X1304790Y1747792D01*
X1303705Y1747375D01*
X1302465Y1747792D01*
X1301380Y1749041D01*
X1300760Y1750917D01*
X1300605Y1753000D01*
X1300915Y1755708D01*
X1301380Y1757167D01*
X1302155Y1758625D01*
X1303240Y1759667D01*
X1304325Y1759875D01*
X1305410Y1759458D01*
X1306185Y1758417D01*
G01X1278750Y1807075D02*
Y1819575D01*
X1276890Y1817075D01*
G01Y1807075D02*
X1280610D01*
G01X1287740Y1808950D02*
X1288670Y1807908D01*
X1289755Y1807283D01*
X1291150Y1807075D01*
X1292545Y1807492D01*
X1293630Y1808325D01*
X1294405Y1809783D01*
X1294560Y1811450D01*
X1294250Y1813117D01*
X1293475Y1814158D01*
X1292390Y1814992D01*
X1291305Y1815200D01*
X1290220Y1814992D01*
X1288825Y1814158D01*
X1289290Y1819575D01*
X1293475D01*
G01X1303550Y1807075D02*
X1304635Y1807283D01*
X1305875Y1807908D01*
X1306650Y1808950D01*
X1306960Y1810408D01*
X1306650Y1811866D01*
X1305720Y1813117D01*
X1304325Y1813742D01*
X1302775D01*
X1301845Y1814158D01*
X1301070Y1815200D01*
X1300760Y1816658D01*
X1301225Y1818117D01*
X1302310Y1819158D01*
X1303550Y1819575D01*
X1304790Y1819158D01*
X1305875Y1818117D01*
X1306340Y1816658D01*
X1306030Y1815200D01*
X1305255Y1814158D01*
X1304325Y1813742D01*
X1302775D01*
X1301380Y1813117D01*
X1300450Y1811866D01*
X1300140Y1810408D01*
X1300450Y1808950D01*
X1301225Y1807908D01*
X1302465Y1807283D01*
X1303550Y1807075D01*
G01X1312540Y1809575D02*
X1313470Y1808116D01*
X1314710Y1807283D01*
X1316105Y1807075D01*
X1317345Y1807283D01*
X1318585Y1808325D01*
X1319360Y1809575D01*
X1319515Y1810825D01*
X1319205Y1812283D01*
X1318120Y1813325D01*
X1317035Y1813742D01*
X1315640D01*
G01X1317035D02*
X1317965Y1814367D01*
X1318740Y1815408D01*
X1319050Y1816658D01*
X1318740Y1817908D01*
X1317965Y1818950D01*
X1316570Y1819575D01*
X1315175Y1819367D01*
X1313780Y1818533D01*
G01X1284950Y1867450D02*
X1283710Y1867658D01*
X1282625Y1868491D01*
X1281695Y1869742D01*
X1281075Y1871200D01*
X1280765Y1872867D01*
Y1874533D01*
X1281075Y1876200D01*
X1281695Y1877658D01*
X1282625Y1878908D01*
X1283710Y1879742D01*
X1284950Y1879950D01*
X1286190Y1879742D01*
X1287275Y1878908D01*
X1288205Y1877658D01*
X1288825Y1876200D01*
X1289135Y1874533D01*
Y1872867D01*
X1288825Y1871200D01*
X1288205Y1869742D01*
X1287275Y1868491D01*
X1286190Y1867658D01*
X1284950Y1867450D01*
G01X1286190Y1870783D02*
X1288050Y1867450D01*
G01X1297350Y1879950D02*
Y1867450D01*
G01X1293785Y1879950D02*
X1300915D01*
G01X1309750Y1867450D02*
Y1873075D01*
X1306650Y1879950D01*
G01X1312850D02*
X1309750Y1873075D01*
G01X1281540Y1838800D02*
X1282470Y1837758D01*
X1283555Y1837133D01*
X1284950Y1836925D01*
X1286345Y1837342D01*
X1287430Y1838175D01*
X1288205Y1839633D01*
X1288360Y1841300D01*
X1288050Y1842967D01*
X1287275Y1844008D01*
X1286190Y1844842D01*
X1285105Y1845050D01*
X1284020Y1844842D01*
X1282625Y1844008D01*
X1283090Y1849425D01*
X1287275D01*
G01X1297350D02*
X1296110Y1849008D01*
X1295180Y1847967D01*
X1294560Y1846717D01*
X1294095Y1845050D01*
X1293940Y1843175D01*
X1294095Y1841300D01*
X1294560Y1839633D01*
X1295180Y1838383D01*
X1296110Y1837342D01*
X1297350Y1836925D01*
X1298590Y1837342D01*
X1299520Y1838383D01*
X1300140Y1839633D01*
X1300605Y1841300D01*
X1300760Y1843175D01*
X1300605Y1845050D01*
X1300140Y1846717D01*
X1299520Y1847967D01*
X1298590Y1849008D01*
X1297350Y1849425D01*
G01X1309750D02*
X1308510Y1849008D01*
X1307580Y1847967D01*
X1306960Y1846717D01*
X1306495Y1845050D01*
X1306340Y1843175D01*
X1306495Y1841300D01*
X1306960Y1839633D01*
X1307580Y1838383D01*
X1308510Y1837342D01*
X1309750Y1836925D01*
X1310990Y1837342D01*
X1311920Y1838383D01*
X1312540Y1839633D01*
X1313005Y1841300D01*
X1313160Y1843175D01*
X1313005Y1845050D01*
X1312540Y1846717D01*
X1311920Y1847967D01*
X1310990Y1849008D01*
X1309750Y1849425D01*
G54D15*
X31299Y230866D03*
Y220866D03*
Y210866D03*
Y338563D03*
Y358563D03*
Y348563D03*
Y903917D03*
Y923917D03*
Y913917D03*
Y1054587D03*
Y1044587D03*
Y1064587D03*
Y1619941D03*
Y1609941D03*
Y1629941D03*
Y1757638D03*
Y1747638D03*
Y1737638D03*
X897450Y1783475D03*
G54D16*
X26450Y274750D03*
X25500Y321200D03*
X21600Y333800D03*
X29500Y343500D03*
X23100Y342400D03*
X23400Y353500D03*
X29500Y410500D03*
X14000Y476000D03*
X28800Y533700D03*
X5304Y548800D03*
Y528900D03*
X5094Y574500D03*
X29500Y586500D03*
X23450Y577491D03*
X25148Y570800D03*
X27000Y573800D03*
X4594Y749000D03*
Y714000D03*
X5094Y1354500D03*
X26700Y1529800D03*
X28000Y1596800D03*
X13300Y1644300D03*
X10500Y1648800D03*
X13300Y1689600D03*
X19542Y1710518D03*
X29100Y1721550D03*
X19200Y1707000D03*
X25000Y1763800D03*
X26750Y1791100D03*
X27400Y1899400D03*
X70454Y60031D03*
X64500Y53000D03*
X64000Y67553D03*
X74000Y60500D03*
X79000Y65500D03*
X75000Y67500D03*
X81500Y75500D03*
X63500Y63500D03*
X59600Y125800D03*
X75300Y155300D03*
X49924Y153261D03*
X53000Y171500D03*
X65000Y166300D03*
X60350Y151950D03*
X39300Y181100D03*
X63500Y179300D03*
X53400Y191300D03*
X39300Y175500D03*
X43700Y181200D03*
X43400Y174325D03*
X32425Y177900D03*
X52700Y162300D03*
X64400Y183400D03*
X52500Y175200D03*
X70500Y190200D03*
X54400Y217000D03*
X65200Y207850D03*
X57424Y232974D03*
X42720Y233990D03*
X65000Y241500D03*
Y235400D03*
X54200Y220700D03*
Y207850D03*
X51700Y234800D03*
X41100Y231000D03*
X71400Y208150D03*
X69900Y236600D03*
X77900Y229034D03*
X70600Y217600D03*
X74800Y231800D03*
X69400Y226100D03*
X61300Y229400D03*
X38000Y228500D03*
X75300Y211300D03*
X72100Y221700D03*
X49700Y209700D03*
X53500Y199700D03*
X47800Y199200D03*
X64000Y199700D03*
X60300Y275700D03*
X57500Y268500D03*
X68000Y268000D03*
X70600Y250500D03*
X48500Y248600D03*
X42500Y254100D03*
X58936Y256289D03*
X36000Y260386D03*
X42500Y260200D03*
X34200Y284800D03*
X52500Y248500D03*
X32600Y290500D03*
X50800Y266400D03*
X54000Y275600D03*
X45800Y277800D03*
X43400Y272300D03*
X32675Y299500D03*
X78000Y429500D03*
X34000Y448000D03*
X33200Y468900D03*
X52100Y513100D03*
X46500Y511000D03*
X46000Y516000D03*
X51000Y529500D03*
X71445Y532192D03*
X72397Y528297D03*
X77800Y540300D03*
X33450Y574300D03*
X63400Y581400D03*
X49700Y568900D03*
X66000Y550500D03*
X65000Y561500D03*
X78400Y583700D03*
X70350Y558850D03*
X54600Y573400D03*
X75571Y692496D03*
X53000Y673500D03*
X57684Y697639D03*
X64000Y666600D03*
X66200Y653500D03*
X82000Y652000D03*
X52500Y682500D03*
X78494Y697835D03*
X53000Y695100D03*
X39800Y681400D03*
X43388Y694286D03*
X44500Y697500D03*
X60900Y670200D03*
X60500Y682540D03*
X76100Y686900D03*
X73000Y728000D03*
X69000Y726800D03*
X71500Y735500D03*
X73500Y732000D03*
X49500Y703500D03*
X46500Y705500D03*
X57500Y844500D03*
X72400Y822900D03*
X51200Y827000D03*
X61207Y828350D03*
X49600Y889400D03*
X55700Y880000D03*
X59500Y881600D03*
X57500Y890300D03*
X56000Y885500D03*
X64600Y882700D03*
X61600Y885200D03*
X67200Y888800D03*
X54300Y915500D03*
X54000Y996500D03*
X70800Y990500D03*
X57500Y987800D03*
Y984300D03*
X53800Y1006200D03*
X53500Y1025500D03*
X56000Y1021500D03*
X54500Y1035500D03*
X51000Y1018000D03*
X64500Y1099000D03*
X37500Y1099823D03*
X70500Y1161500D03*
X73163Y1158780D03*
X71100Y1171000D03*
X68800Y1178800D03*
X39400Y1381300D03*
X44500Y1380500D03*
X45500Y1400000D03*
X45000Y1428000D03*
X80000Y1472000D03*
X36400Y1523400D03*
X67700Y1568700D03*
X43500Y1620700D03*
X42700Y1606000D03*
X38400Y1596700D03*
X42500Y1673000D03*
X35500Y1670500D03*
X43600Y1668300D03*
X43300Y1646600D03*
X31400Y1648200D03*
X45500Y1690000D03*
X41500Y1692000D03*
X44500Y1678000D03*
X40300Y1703900D03*
X44100Y1685200D03*
X34000Y1691500D03*
X45300Y1776300D03*
X52500Y1756000D03*
X62000Y1877000D03*
X57900Y1899800D03*
X65300Y1886600D03*
X55900Y1881500D03*
X38700Y1893800D03*
X41500Y1889500D03*
X60300Y1892300D03*
X47000Y1886200D03*
X79900Y1923000D03*
X91500Y88500D03*
X97000Y51500D03*
X115500Y59500D03*
X98500Y73000D03*
X109000Y76500D03*
X115000D03*
X99500Y61000D03*
X89500Y49500D03*
X109500Y62000D03*
X84500Y56500D03*
X92500Y73000D03*
X88253Y65500D03*
X93500Y101500D03*
X93900Y111800D03*
X93000Y107000D03*
X91000Y97000D03*
X91500Y92500D03*
X104500Y101000D03*
X112000D03*
X117600Y234900D03*
X122100Y230100D03*
X85676Y231100D03*
X127200Y246000D03*
X122500Y441000D03*
X108100Y477650D03*
X91300Y528200D03*
X108900Y541300D03*
X102700Y541000D03*
X87700Y528000D03*
X132500Y539621D03*
X129000Y597000D03*
X124200Y568400D03*
X119800Y568300D03*
X88000Y586500D03*
X101000Y583000D03*
X96000Y588000D03*
X89000Y595000D03*
X87000Y591000D03*
X121000Y581500D03*
X124900Y582000D03*
X91300Y577000D03*
X92200Y553800D03*
X106300Y553200D03*
X116000Y596900D03*
X113655Y599363D03*
X110400Y550800D03*
X128900Y580500D03*
X122300Y575000D03*
X115300Y551800D03*
X131135Y639554D03*
X84200Y643865D03*
X87000Y648000D03*
X130000Y700500D03*
X122500D03*
X114500D03*
X105500Y702500D03*
X93000Y698500D03*
X88500Y700000D03*
X98000Y698500D03*
X86597Y681103D03*
X100200Y663900D03*
X122500Y653650D03*
X117400Y653100D03*
X118127Y663400D03*
X109005Y665890D03*
X114000Y663350D03*
X83850Y678109D03*
X91250Y704700D03*
X130000Y753000D03*
Y746000D03*
X119500Y746500D03*
Y739500D03*
X113500Y729000D03*
Y736000D03*
Y747000D03*
Y721000D03*
X106000Y709000D03*
X98000Y703000D03*
Y708000D03*
X86500Y723500D03*
X130000Y764000D03*
X119500Y757500D03*
X113500Y756000D03*
X118700Y840700D03*
X98900Y822900D03*
X114900Y824100D03*
X106404Y840700D03*
X100300Y841000D03*
X111500Y851600D03*
X101500Y874200D03*
X102300Y863438D03*
X107164Y862285D03*
X113400Y862200D03*
X125400Y983600D03*
Y992000D03*
X97300Y990800D03*
X83500Y976300D03*
Y972800D03*
X83000Y979800D03*
X94000Y971800D03*
X104000Y1049500D03*
X127200Y1015200D03*
X104000Y1062500D03*
X82094Y1112500D03*
X105000Y1181000D03*
X119500Y1261000D03*
X119000Y1255968D03*
X128700Y1408000D03*
X125000Y1398500D03*
X100860Y1402260D03*
X111000Y1394000D03*
X125100Y1402500D03*
X131174Y1412700D03*
X83200Y1455500D03*
X89000Y1428171D03*
X110000Y1429500D03*
X132000Y1436500D03*
X112750Y1491250D03*
X121000Y1506500D03*
X113000D03*
X117000D03*
X109000D03*
X133000Y1505500D03*
X128999Y1506499D03*
X125000Y1506500D03*
X132300Y1491100D03*
X108500Y1569000D03*
X83000Y1619703D03*
X113200Y1622800D03*
Y1619300D03*
X83050Y1616000D03*
X91100Y1922800D03*
X128900Y1923300D03*
X104600Y1923400D03*
X149500Y52000D03*
X135500Y441000D03*
X146960Y432400D03*
X142000Y478500D03*
X165300Y481100D03*
X144000Y509500D03*
X166100Y527900D03*
X147000Y529900D03*
X162500Y527900D03*
X159850Y541800D03*
X182588Y542288D03*
X159250Y590250D03*
X154600Y581500D03*
X133500Y575500D03*
X145800Y594400D03*
X137000Y589900D03*
X133500Y582000D03*
X134600Y586700D03*
X156300Y552100D03*
X142500Y550000D03*
X135000Y561500D03*
X142100Y581400D03*
X160000Y562500D03*
X147900Y588100D03*
X138900Y650100D03*
X174196Y628196D03*
X139200Y653900D03*
X150978Y687775D03*
X142648Y665429D03*
X165433Y692372D03*
X134600Y665600D03*
X161000Y674000D03*
X157500Y664500D03*
X149000Y677000D03*
X155200Y679500D03*
X161500Y691700D03*
X150700D03*
X166000Y751500D03*
X170000Y745500D03*
X161600Y739800D03*
X161500Y747500D03*
X146000Y726000D03*
X165900Y717300D03*
X147000Y703000D03*
X146000Y738000D03*
X175100Y710000D03*
X158600Y752600D03*
X153192Y705890D03*
X146000Y755000D03*
Y765500D03*
Y796500D03*
Y782500D03*
X166000Y760000D03*
X166500Y775500D03*
X161500Y759000D03*
Y768000D03*
Y778000D03*
X146500Y812000D03*
X146000Y824000D03*
X180000Y856000D03*
X162000Y817500D03*
X174000Y834500D03*
X168000Y830000D03*
X180000Y872500D03*
X179500Y884000D03*
X179900Y900900D03*
X157800Y898000D03*
X147500Y900500D03*
X179900Y925700D03*
X179800Y941400D03*
X180000Y912500D03*
X143000Y953032D03*
X146500Y953030D03*
X149772Y954121D03*
X152747Y952474D03*
X163200Y985200D03*
X163100Y978600D03*
X149800Y1008700D03*
X179000Y1005000D03*
X180000Y960400D03*
X180500Y973200D03*
X150500Y976500D03*
X155000Y974500D03*
X155500Y1030000D03*
X153500Y1033500D03*
X151500Y1030500D03*
X163000Y1042500D03*
X159500Y1062000D03*
X135601Y1416200D03*
X146500Y1397100D03*
X155900D03*
X139900Y1415100D03*
X134500Y1420000D03*
X169000Y1426750D03*
X158500Y1466500D03*
X151500Y1438500D03*
X157500Y1454800D03*
X142500Y1420500D03*
X142000Y1494800D03*
X147500Y1498000D03*
X153500Y1496500D03*
X135008Y1508245D03*
X143518Y1567520D03*
X177500Y1569500D03*
X141500Y1621600D03*
X141300Y1625000D03*
X169876Y1626303D03*
X173270Y1626517D03*
X170000Y1920500D03*
X162100Y1912000D03*
X151900Y1891400D03*
X146300Y1913700D03*
X142400Y1923800D03*
X176700Y1923900D03*
X177700Y1912800D03*
X152500Y1883100D03*
X157900Y1923100D03*
X133500Y1906500D03*
X201500Y165000D03*
X191400Y432405D03*
X202210Y638500D03*
X201500Y691500D03*
X202500Y666000D03*
X201500Y726500D03*
X202500Y755500D03*
X201500Y777000D03*
X201389Y797000D03*
X202500Y822000D03*
Y846500D03*
X202000Y859500D03*
Y890000D03*
X202210Y903500D03*
X202000Y875000D03*
X202500Y945500D03*
X202000Y918000D03*
X201500Y931500D03*
X202500Y1006000D03*
Y977500D03*
Y962000D03*
X201500Y991000D03*
X202000Y1037000D03*
Y1052000D03*
X201500Y1019000D03*
X201389Y1067000D03*
X201500Y1082500D03*
X195000Y1112000D03*
X201500Y1147000D03*
X202000Y1212000D03*
X202500Y1179000D03*
X202000Y1246000D03*
X201500Y1310000D03*
X202500Y1280000D03*
X201500Y1359500D03*
X200700Y1348500D03*
X201700Y1388300D03*
X201500Y1413000D03*
X202400Y1444000D03*
X201389Y1425500D03*
X202210Y1462000D03*
X201500Y1569000D03*
X202000Y1537500D03*
X202210Y1554000D03*
X187500Y1559500D03*
X196500Y1606500D03*
X191700Y1652700D03*
X192500Y1648000D03*
X192650Y1641500D03*
X200500Y1876500D03*
X184500Y1920500D03*
X201200Y1890500D03*
X201100Y1908800D03*
X897450Y1843175D03*
G54D17*
X27559Y629921D03*
X17716Y1338583D03*
X27559Y1811023D03*
X179134Y78740D03*
X179133Y570866D03*
X179134Y1161417D03*
X897450Y1693925D03*
G54D18*
X47244Y68110D03*
Y501338D03*
Y761181D03*
Y1207323D03*
Y1467165D03*
Y1900393D03*
X897450Y1574525D03*
G54D19*
X80709Y119409D03*
Y329409D03*
X149606Y119409D03*
Y329409D03*
X897450Y1544675D03*
M02*
